G04 ================== begin FILE IDENTIFICATION RECORD ==================*
G04 Layout Name:  D:/<user>/Wistron_project/16315-1/gbr/16315-1.brd*
G04 Film Name:    BACKDRILL_1_6*
G04 File Format:  Gerber RS274X*
G04 File Origin:  Cadence Allegro 16.5-S056*
G04 Origin Date:  Fri Jun 09 15:31:04 2017*
G04 *
G04 Layer:  MANUFACTURING/NCBACKDRILL-1-6*
G04 Layer:  DRAWING FORMAT/BACK_DRILL_1_6*
G04 Layer:  DRAWING FORMAT/LAYER_PCB_STORY*
G04 Layer:  BOARD GEOMETRY/PANEL_OUTLINE*
G04 *
G04 Offset:    (0.00 0.00)*
G04 Mirror:    No*
G04 Mode:      Positive*
G04 Rotation:  0*
G04 FullContactRelief:  No*
G04 UndefLineWidth:     6.00*
G04 ================== end FILE IDENTIFICATION RECORD ====================*
%FSLAX35Y35*MOIN*%
%IR0*IPPOS*OFA0.00000B0.00000*MIA0B0*SFA1.00000B1.00000*%
%AMMACRO10*
1,1,.006,.002935,-.007085*
20,1,.006,.002935,-.007085,-.002935,-.007085,0.0*
1,1,.006,-.002935,-.007085*
20,1,.006,-.002935,-.007085,-.007085,-.002935,0.0*
1,1,.006,-.007085,-.002935*
20,1,.006,-.007085,-.002935,-.007085,.002935,0.0*
1,1,.006,-.007085,.002935*
20,1,.006,-.007085,.002935,-.002935,.007085,0.0*
1,1,.006,-.002935,.007085*
20,1,.006,-.002935,.007085,.002935,.007085,0.0*
1,1,.006,.002935,.007085*
20,1,.006,.002935,.007085,.007085,.002935,0.0*
1,1,.006,.007085,.002935*
20,1,.006,.007085,.002935,.007085,-.002935,0.0*
1,1,.006,.007085,-.002935*
20,1,.006,.007085,-.002935,.002935,-.007085,0.0*
1,1,.006,.002935,-.007085*
1,1,.006,-.0026,-.00248*
20,1,.006,-.0026,-.00248,-.00189,-.00307,0.0*
1,1,.006,-.00189,-.00307*
20,1,.006,-.00189,-.00307,-.00106,-.00342,0.0*
1,1,.006,-.00106,-.00342*
20,1,.006,-.00106,-.00342,0.0,-.00354,0.0*
1,1,.006,0.0,-.00354*
20,1,.006,0.0,-.00354,.00106,-.0033,0.0*
1,1,.006,.00106,-.0033*
20,1,.006,.00106,-.0033,.00189,-.00283,0.0*
1,1,.006,.00189,-.00283*
20,1,.006,.00189,-.00283,.00248,-.00201,0.0*
1,1,.006,.00248,-.00201*
20,1,.006,.00248,-.00201,.0026,-.00106,0.0*
1,1,.006,.0026,-.00106*
20,1,.006,.0026,-.00106,.00236,-.00012,0.0*
1,1,.006,.00236,-.00012*
20,1,.006,.00236,-.00012,.00177,.00047,0.0*
1,1,.006,.00177,.00047*
20,1,.006,.00177,.00047,.00094,.00094,0.0*
1,1,.006,.00094,.00094*
20,1,.006,.00094,.00094,.00012,.00106,0.0*
1,1,.006,.00012,.00106*
20,1,.006,.00012,.00106,-.00071,.00094,0.0*
1,1,.006,-.00071,.00094*
20,1,.006,-.00071,.00094,-.00177,.00047,0.0*
1,1,.006,-.00177,.00047*
20,1,.006,-.00177,.00047,-.00142,.00354,0.0*
1,1,.006,-.00142,.00354*
20,1,.006,-.00142,.00354,.00177,.00354,0.0*
1,1,.006,.00177,.00354*
%
%ADD10MACRO10*%
%ADD11C,.02*%
%ADD12C,.006*%
G75*
%LPD*%
G75*
G54D10*
X429724Y68307D03*
X458071D03*
X443898D03*
X458071Y87993D03*
Y82481D03*
Y73819D03*
X429724Y87993D03*
Y82481D03*
Y73819D03*
X450984Y91930D03*
Y86418D03*
X443898Y87993D03*
Y82481D03*
X436811Y91930D03*
Y86418D03*
X450984Y77756D03*
Y72245D03*
X443898Y73819D03*
X436811Y77756D03*
Y72245D03*
X472244Y68307D03*
X479331Y91930D03*
Y86418D03*
X472244Y87993D03*
Y82481D03*
X465157Y91930D03*
Y86418D03*
X479331Y77756D03*
Y72245D03*
X472244Y73819D03*
X465157Y77756D03*
Y72245D03*
X514764Y68307D03*
X543110D03*
X528937D03*
X514764Y87993D03*
Y82481D03*
Y73819D03*
X550197Y91930D03*
Y86418D03*
X543110Y87993D03*
Y82481D03*
X536024Y91930D03*
Y86418D03*
X528937Y87993D03*
Y82481D03*
X521850Y91930D03*
Y86418D03*
X550197Y77756D03*
Y72245D03*
X543110Y73819D03*
X536024Y77756D03*
Y72245D03*
X528937Y73819D03*
X521850Y77756D03*
Y72245D03*
X557283Y68307D03*
X564370Y91930D03*
Y86418D03*
X557283Y87993D03*
Y82481D03*
X564370Y77756D03*
Y72245D03*
X557283Y73819D03*
X1398228Y68307D03*
X1426575D03*
X1412402D03*
X1426575Y87993D03*
Y82481D03*
Y73819D03*
X1398228Y87993D03*
Y82481D03*
Y73819D03*
X1419488Y91930D03*
Y86418D03*
X1412402Y87993D03*
Y82481D03*
X1405315Y91930D03*
Y86418D03*
X1419488Y77756D03*
Y72245D03*
X1412402Y73819D03*
X1405315Y77756D03*
Y72245D03*
X1440748Y68307D03*
X1447835Y91930D03*
Y86418D03*
X1440748Y87993D03*
Y82481D03*
X1433661Y91930D03*
Y86418D03*
X1447835Y77756D03*
Y72245D03*
X1440748Y73819D03*
X1433661Y77756D03*
Y72245D03*
X1483268Y68307D03*
X1511614D03*
X1497441D03*
X1483268Y87993D03*
Y82481D03*
Y73819D03*
X1518701Y91930D03*
Y86418D03*
X1511614Y87993D03*
Y82481D03*
X1504528Y91930D03*
Y86418D03*
X1497441Y87993D03*
Y82481D03*
X1490354Y91930D03*
Y86418D03*
X1518701Y77756D03*
Y72245D03*
X1511614Y73819D03*
X1504528Y77756D03*
Y72245D03*
X1497441Y73819D03*
X1490354Y77756D03*
Y72245D03*
X1525787Y68307D03*
X1532874Y91930D03*
Y86418D03*
X1525787Y87993D03*
Y82481D03*
X1532874Y77756D03*
Y72245D03*
X1525787Y73819D03*
X2402246Y1672064D03*
G54D11*
G01X363248Y-425196D02*
Y-505196D01*
G01D02*
X1639148D01*
G01X359248Y-409196D02*
G02I-12000J0D01*
G01X354098D02*
G02I-6850J0D01*
G01X347248Y-425196D02*
Y-393196D01*
G01X363248Y-425196D02*
X1639148D01*
G01X363248Y-460696D02*
X1639148D01*
G01X363248Y-409196D02*
X331248D01*
G01X720748Y-425196D02*
Y-505196D01*
G01X858248Y-425196D02*
Y-505196D01*
G01X973248Y-425196D02*
Y-505196D01*
G01X1271648Y-425196D02*
Y-505196D01*
G01X1441648Y-425196D02*
Y-505196D01*
G01X1639148Y-425196D02*
Y-505196D01*
G01X1667148Y-409196D02*
G02I-12000J0D01*
G01X1661998D02*
G02I-6850J0D01*
G01X1655148Y-425196D02*
Y-393196D01*
G01X1671148Y-409196D02*
X1639148D01*
G54D12*
G01X394744Y-485863D02*
X395618Y-484988D01*
X396273Y-483530D01*
X396710Y-481487D01*
X396273Y-479738D01*
X395400Y-478571D01*
X393871Y-477696D01*
X387976D01*
Y-495196D01*
X395181D01*
X396710Y-494030D01*
X397583Y-492279D01*
X398020Y-490238D01*
X397583Y-488196D01*
X396273Y-486446D01*
X394744Y-485863D01*
X387976D01*
G01X407441Y-495196D02*
Y-483530D01*
G01Y-485863D02*
X408533Y-484696D01*
X409625Y-483821D01*
X411153Y-483530D01*
X412244Y-483821D01*
X413555Y-484696D01*
G01X423413Y-500446D02*
X424723Y-501029D01*
X426470Y-500446D01*
X427561Y-499280D01*
X428435Y-497821D01*
X429744Y-493155D01*
X432583Y-483530D01*
G01X425596D02*
X429744Y-493155D01*
G01X448991Y-484988D02*
X447463Y-483821D01*
X446153Y-483530D01*
X444406Y-484113D01*
X443096Y-485279D01*
X442223Y-487321D01*
X442004Y-489363D01*
X442223Y-491405D01*
X443096Y-493155D01*
X444406Y-494613D01*
X446153Y-495196D01*
X447681Y-494613D01*
X448991Y-493446D01*
G01X459723Y-487321D02*
X466710D01*
X466055Y-485279D01*
X464963Y-484113D01*
X463435Y-483530D01*
X461906Y-483821D01*
X460596Y-484696D01*
X459723Y-486738D01*
X459286Y-488488D01*
Y-490238D01*
X459723Y-491988D01*
X460815Y-493738D01*
X462125Y-494904D01*
X463653Y-495196D01*
X465181Y-494613D01*
X466710Y-492863D01*
G01X502801Y-479155D02*
X501491Y-478279D01*
X499963Y-477696D01*
X498216D01*
X496251Y-478571D01*
X494723Y-480029D01*
X493631Y-481780D01*
X492758Y-484696D01*
X492539Y-487321D01*
X492976Y-489946D01*
X493631Y-491696D01*
X494941Y-493446D01*
X496470Y-494613D01*
X497998Y-495196D01*
X499526D01*
X501055Y-494613D01*
X502365Y-493738D01*
X503457Y-492572D01*
G01X519428Y-495196D02*
Y-483530D01*
G01Y-485571D02*
X518555Y-484405D01*
X517244Y-483821D01*
X515716Y-483530D01*
X514188Y-484113D01*
X512878Y-485279D01*
X512004Y-487029D01*
X511568Y-489363D01*
X512004Y-491696D01*
X512878Y-493446D01*
X514188Y-494613D01*
X515716Y-495196D01*
X517244Y-494904D01*
X518555Y-494030D01*
X519428Y-492863D01*
G01X529286Y-495196D02*
Y-483530D01*
G01Y-486446D02*
X530160Y-484988D01*
X531470Y-483821D01*
X533216Y-483530D01*
X534744Y-483821D01*
X536055Y-484988D01*
X536710Y-487029D01*
Y-495196D01*
G01X545913Y-500446D02*
X547223Y-501029D01*
X548970Y-500446D01*
X550061Y-499280D01*
X550935Y-497821D01*
X552244Y-493155D01*
X555083Y-483530D01*
G01X548096D02*
X552244Y-493155D01*
G01X567998Y-495196D02*
X566688Y-494904D01*
X565378Y-493738D01*
X564504Y-491696D01*
X564068Y-489363D01*
X564504Y-487029D01*
X565378Y-484988D01*
X566688Y-483821D01*
X567998Y-483530D01*
X569308Y-483821D01*
X570618Y-484988D01*
X571491Y-487029D01*
X571710Y-489363D01*
X571491Y-491696D01*
X570618Y-493738D01*
X569308Y-494904D01*
X567998Y-495196D01*
G01X581786D02*
Y-483530D01*
G01Y-486446D02*
X582660Y-484988D01*
X583970Y-483821D01*
X585716Y-483530D01*
X587244Y-483821D01*
X588555Y-484988D01*
X589210Y-487029D01*
Y-495196D01*
G01X616350D02*
Y-477696D01*
X624646D01*
G01X621590Y-486154D02*
X616350D01*
G01X637998Y-495779D02*
X637561Y-495488D01*
Y-494904D01*
X637998Y-494613D01*
X638435Y-494904D01*
Y-495488D01*
X637998Y-495779D01*
G01X650695Y-495196D02*
Y-477696D01*
X655061D01*
X656808Y-478571D01*
X658118Y-479738D01*
X659210Y-481487D01*
X660083Y-483530D01*
X660301Y-486446D01*
X660083Y-489363D01*
X659210Y-491405D01*
X658118Y-493155D01*
X656808Y-494321D01*
X655061Y-495196D01*
X650695D01*
G01X668631D02*
Y-477696D01*
X673871D01*
X675618Y-478571D01*
X676928Y-480613D01*
X677365Y-482946D01*
X676928Y-485279D01*
X675836Y-487029D01*
X673871Y-487905D01*
X668631D01*
G01X692244Y-485863D02*
X693118Y-484988D01*
X693773Y-483530D01*
X694210Y-481487D01*
X693773Y-479738D01*
X692900Y-478571D01*
X691371Y-477696D01*
X685476D01*
Y-495196D01*
X692681D01*
X694210Y-494030D01*
X695083Y-492279D01*
X695520Y-490238D01*
X695083Y-488196D01*
X693773Y-486446D01*
X692244Y-485863D01*
X685476D01*
G01X501071Y-450196D02*
Y-432696D01*
X506748Y-447279D01*
X512425Y-432696D01*
Y-450196D01*
G01X524248D02*
X522938Y-449904D01*
X521628Y-448738D01*
X520754Y-446696D01*
X520318Y-444363D01*
X520754Y-442029D01*
X521628Y-439988D01*
X522938Y-438821D01*
X524248Y-438530D01*
X525558Y-438821D01*
X526868Y-439988D01*
X527741Y-442029D01*
X527960Y-444363D01*
X527741Y-446696D01*
X526868Y-448738D01*
X525558Y-449904D01*
X524248Y-450196D01*
G01X545678Y-432696D02*
Y-450196D01*
G01Y-447572D02*
X544805Y-449030D01*
X543494Y-449904D01*
X541966Y-450196D01*
X540220Y-449613D01*
X538910Y-448155D01*
X538036Y-446405D01*
X537818Y-444363D01*
X538036Y-442321D01*
X538910Y-440571D01*
X540220Y-439113D01*
X541966Y-438530D01*
X543494Y-438821D01*
X544586Y-439405D01*
X545678Y-440571D01*
G01X555973Y-442321D02*
X562960D01*
X562305Y-440279D01*
X561213Y-439113D01*
X559685Y-438530D01*
X558156Y-438821D01*
X556846Y-439696D01*
X555973Y-441738D01*
X555536Y-443488D01*
Y-445238D01*
X555973Y-446988D01*
X557065Y-448738D01*
X558375Y-449904D01*
X559903Y-450196D01*
X561431Y-449613D01*
X562960Y-447863D01*
G01X576748Y-450196D02*
Y-432696D01*
G01X754448Y-495196D02*
Y-477696D01*
X751828Y-481196D01*
G01Y-495196D02*
X757068D01*
G01X767800Y-487905D02*
X769328Y-485863D01*
X770638Y-484696D01*
X772385Y-484113D01*
X773913Y-484696D01*
X775005Y-485863D01*
X775878Y-487613D01*
X776096Y-489654D01*
X775878Y-491405D01*
X775005Y-493155D01*
X773694Y-494613D01*
X772166Y-495196D01*
X770420Y-494613D01*
X768891Y-492863D01*
X768018Y-490238D01*
X767800Y-487321D01*
X768236Y-483530D01*
X768891Y-481487D01*
X769983Y-479446D01*
X771511Y-477988D01*
X773040Y-477696D01*
X774568Y-478279D01*
X775660Y-479738D01*
G01X784645Y-491696D02*
X785954Y-493738D01*
X787701Y-494904D01*
X789666Y-495196D01*
X791413Y-494904D01*
X793160Y-493446D01*
X794251Y-491696D01*
X794470Y-489946D01*
X794033Y-487905D01*
X792505Y-486446D01*
X790976Y-485863D01*
X789011D01*
G01X790976D02*
X792286Y-484988D01*
X793378Y-483530D01*
X793815Y-481780D01*
X793378Y-480029D01*
X792286Y-478571D01*
X790321Y-477696D01*
X788356Y-477988D01*
X786391Y-479155D01*
G01X806948Y-495196D02*
Y-477696D01*
X804328Y-481196D01*
G01Y-495196D02*
X809568D01*
G01X819645Y-492572D02*
X820954Y-494030D01*
X822483Y-494904D01*
X824448Y-495196D01*
X826413Y-494613D01*
X827941Y-493446D01*
X829033Y-491405D01*
X829251Y-489071D01*
X828815Y-486738D01*
X827723Y-485279D01*
X826194Y-484113D01*
X824666Y-483821D01*
X823138Y-484113D01*
X821173Y-485279D01*
X821828Y-477696D01*
X827723D01*
G01X741331Y-450196D02*
Y-432696D01*
X746571D01*
X748318Y-433571D01*
X749628Y-435613D01*
X750065Y-437946D01*
X749628Y-440279D01*
X748536Y-442029D01*
X746571Y-442905D01*
X741331D01*
G01X768001Y-434155D02*
X766691Y-433279D01*
X765163Y-432696D01*
X763416D01*
X761451Y-433571D01*
X759923Y-435029D01*
X758831Y-436780D01*
X757958Y-439696D01*
X757739Y-442321D01*
X758176Y-444946D01*
X758831Y-446696D01*
X760141Y-448446D01*
X761670Y-449613D01*
X763198Y-450196D01*
X764726D01*
X766255Y-449613D01*
X767565Y-448738D01*
X768657Y-447572D01*
G01X782444Y-440863D02*
X783318Y-439988D01*
X783973Y-438530D01*
X784410Y-436487D01*
X783973Y-434738D01*
X783100Y-433571D01*
X781571Y-432696D01*
X775676D01*
Y-450196D01*
X782881D01*
X784410Y-449030D01*
X785283Y-447279D01*
X785720Y-445238D01*
X785283Y-443196D01*
X783973Y-441446D01*
X782444Y-440863D01*
X775676D01*
G01X791648Y-456029D02*
X804748D01*
G01X810676Y-450196D02*
Y-432696D01*
X820720Y-450196D01*
Y-432696D01*
G01X833198Y-450196D02*
X831451Y-449904D01*
X829923Y-448738D01*
X828613Y-446988D01*
X827739Y-444946D01*
X827303Y-442613D01*
Y-440279D01*
X827739Y-437946D01*
X828613Y-435904D01*
X829923Y-434155D01*
X831451Y-432988D01*
X833198Y-432696D01*
X834944Y-432988D01*
X836473Y-434155D01*
X837783Y-435904D01*
X838657Y-437946D01*
X839093Y-440279D01*
Y-442613D01*
X838657Y-444946D01*
X837783Y-446988D01*
X836473Y-448738D01*
X834944Y-449904D01*
X833198Y-450196D01*
G01X884039Y-432696D02*
X889498Y-450196D01*
X894957Y-432696D01*
G01X911365Y-450196D02*
X902631D01*
Y-432696D01*
X911365D01*
G01X907871Y-441154D02*
X902631D01*
G01X920131Y-450196D02*
Y-432696D01*
X925590D01*
X927336Y-433571D01*
X928428Y-434738D01*
X928865Y-437071D01*
X928428Y-439405D01*
X927118Y-440863D01*
X925590Y-441738D01*
X920131D01*
G01X925590D02*
X928865Y-450196D01*
G01X941998Y-450779D02*
X941561Y-450488D01*
Y-449904D01*
X941998Y-449613D01*
X942435Y-449904D01*
Y-450488D01*
X941998Y-450779D01*
G01X915748Y-495196D02*
Y-477696D01*
X913128Y-481196D01*
G01Y-495196D02*
X918368D01*
G01X1019094Y-485863D02*
X1019968Y-484988D01*
X1020623Y-483530D01*
X1021060Y-481487D01*
X1020623Y-479738D01*
X1019750Y-478571D01*
X1018221Y-477696D01*
X1012326D01*
Y-495196D01*
X1019531D01*
X1021060Y-494030D01*
X1021933Y-492279D01*
X1022370Y-490238D01*
X1021933Y-488196D01*
X1020623Y-486446D01*
X1019094Y-485863D01*
X1012326D01*
G01X1029389Y-495196D02*
X1034848Y-477696D01*
X1040307Y-495196D01*
G01X1038341Y-489071D02*
X1031354D01*
G01X1057151Y-479155D02*
X1055841Y-478279D01*
X1054313Y-477696D01*
X1052566D01*
X1050601Y-478571D01*
X1049073Y-480029D01*
X1047981Y-481780D01*
X1047108Y-484696D01*
X1046889Y-487321D01*
X1047326Y-489946D01*
X1047981Y-491696D01*
X1049291Y-493446D01*
X1050820Y-494613D01*
X1052348Y-495196D01*
X1053876D01*
X1055405Y-494613D01*
X1056715Y-493738D01*
X1057807Y-492572D01*
G01X1065045Y-495196D02*
Y-477696D01*
G01X1073341D02*
X1065045Y-488488D01*
G01X1074651Y-495196D02*
X1068756Y-483530D01*
G01X1082545Y-495196D02*
Y-477696D01*
X1086911D01*
X1088658Y-478571D01*
X1089968Y-479738D01*
X1091060Y-481487D01*
X1091933Y-483530D01*
X1092151Y-486446D01*
X1091933Y-489363D01*
X1091060Y-491405D01*
X1089968Y-493155D01*
X1088658Y-494321D01*
X1086911Y-495196D01*
X1082545D01*
G01X1100481D02*
Y-477696D01*
X1105940D01*
X1107686Y-478571D01*
X1108778Y-479738D01*
X1109215Y-482071D01*
X1108778Y-484405D01*
X1107468Y-485863D01*
X1105940Y-486738D01*
X1100481D01*
G01X1105940D02*
X1109215Y-495196D01*
G01X1119728Y-477696D02*
X1124968D01*
G01X1122348D02*
Y-495196D01*
G01X1119728D02*
X1124968D01*
G01X1135481Y-477696D02*
Y-495196D01*
X1144215D01*
G01X1152981Y-477696D02*
Y-495196D01*
X1161715D01*
G01X1168298Y-501029D02*
X1181398D01*
G01X1192348Y-495196D02*
Y-477696D01*
X1189728Y-481196D01*
G01Y-495196D02*
X1194968D01*
G01X1203298Y-501029D02*
X1216398D01*
G01X1223200Y-487905D02*
X1224728Y-485863D01*
X1226038Y-484696D01*
X1227785Y-484113D01*
X1229313Y-484696D01*
X1230405Y-485863D01*
X1231278Y-487613D01*
X1231496Y-489654D01*
X1231278Y-491405D01*
X1230405Y-493155D01*
X1229094Y-494613D01*
X1227566Y-495196D01*
X1225820Y-494613D01*
X1224291Y-492863D01*
X1223418Y-490238D01*
X1223200Y-487321D01*
X1223636Y-483530D01*
X1224291Y-481487D01*
X1225383Y-479446D01*
X1226911Y-477988D01*
X1228440Y-477696D01*
X1229968Y-478279D01*
X1231060Y-479738D01*
G01X1082981Y-432696D02*
Y-450196D01*
X1091715D01*
G01X1108778D02*
Y-438530D01*
G01Y-440571D02*
X1107905Y-439405D01*
X1106594Y-438821D01*
X1105066Y-438530D01*
X1103538Y-439113D01*
X1102228Y-440279D01*
X1101354Y-442029D01*
X1100918Y-444363D01*
X1101354Y-446696D01*
X1102228Y-448446D01*
X1103538Y-449613D01*
X1105066Y-450196D01*
X1106594Y-449904D01*
X1107905Y-449030D01*
X1108778Y-447863D01*
G01X1117763Y-455446D02*
X1119073Y-456029D01*
X1120820Y-455446D01*
X1121911Y-454280D01*
X1122785Y-452821D01*
X1124094Y-448155D01*
X1126933Y-438530D01*
G01X1119946D02*
X1124094Y-448155D01*
G01X1136573Y-442321D02*
X1143560D01*
X1142905Y-440279D01*
X1141813Y-439113D01*
X1140285Y-438530D01*
X1138756Y-438821D01*
X1137446Y-439696D01*
X1136573Y-441738D01*
X1136136Y-443488D01*
Y-445238D01*
X1136573Y-446988D01*
X1137665Y-448738D01*
X1138975Y-449904D01*
X1140503Y-450196D01*
X1142031Y-449613D01*
X1143560Y-447863D01*
G01X1154291Y-450196D02*
Y-438530D01*
G01Y-440863D02*
X1155383Y-439696D01*
X1156475Y-438821D01*
X1158003Y-438530D01*
X1159094Y-438821D01*
X1160405Y-439696D01*
G01X1312898Y-495196D02*
X1311151Y-494904D01*
X1309623Y-493738D01*
X1308313Y-491988D01*
X1307439Y-489946D01*
X1307003Y-487613D01*
Y-485279D01*
X1307439Y-482946D01*
X1308313Y-480904D01*
X1309623Y-479155D01*
X1311151Y-477988D01*
X1312898Y-477696D01*
X1314644Y-477988D01*
X1316173Y-479155D01*
X1317483Y-480904D01*
X1318357Y-482946D01*
X1318793Y-485279D01*
Y-487613D01*
X1318357Y-489946D01*
X1317483Y-491988D01*
X1316173Y-493738D01*
X1314644Y-494904D01*
X1312898Y-495196D01*
G01X1314644Y-490529D02*
X1317265Y-495196D01*
G01X1325595Y-477696D02*
Y-490238D01*
X1326468Y-492863D01*
X1328215Y-494613D01*
X1330398Y-495196D01*
X1332581Y-494613D01*
X1334328Y-492863D01*
X1335201Y-490238D01*
Y-477696D01*
G01X1345278D02*
X1350518D01*
G01X1347898D02*
Y-495196D01*
G01X1345278D02*
X1350518D01*
G01X1360376D02*
Y-477696D01*
X1370420Y-495196D01*
Y-477696D01*
G01X1387701Y-479155D02*
X1386391Y-478279D01*
X1384863Y-477696D01*
X1383116D01*
X1381151Y-478571D01*
X1379623Y-480029D01*
X1378531Y-481780D01*
X1377658Y-484696D01*
X1377439Y-487321D01*
X1377876Y-489946D01*
X1378531Y-491696D01*
X1379841Y-493446D01*
X1381370Y-494613D01*
X1382898Y-495196D01*
X1384426D01*
X1385955Y-494613D01*
X1387265Y-493738D01*
X1388357Y-492572D01*
G01X1400398Y-495196D02*
Y-487321D01*
X1396031Y-477696D01*
G01X1404765D02*
X1400398Y-487321D01*
G01X1290595Y-450196D02*
Y-432696D01*
X1294961D01*
X1296708Y-433571D01*
X1298018Y-434738D01*
X1299110Y-436487D01*
X1299983Y-438530D01*
X1300201Y-441446D01*
X1299983Y-444363D01*
X1299110Y-446405D01*
X1298018Y-448155D01*
X1296708Y-449321D01*
X1294961Y-450196D01*
X1290595D01*
G01X1309623Y-442321D02*
X1316610D01*
X1315955Y-440279D01*
X1314863Y-439113D01*
X1313335Y-438530D01*
X1311806Y-438821D01*
X1310496Y-439696D01*
X1309623Y-441738D01*
X1309186Y-443488D01*
Y-445238D01*
X1309623Y-446988D01*
X1310715Y-448738D01*
X1312025Y-449904D01*
X1313553Y-450196D01*
X1315081Y-449613D01*
X1316610Y-447863D01*
G01X1327123Y-448155D02*
X1328215Y-449321D01*
X1329743Y-450196D01*
X1331053D01*
X1332363Y-449613D01*
X1333236Y-448738D01*
X1333673Y-447572D01*
X1333455Y-445821D01*
X1332581Y-444946D01*
X1328651Y-443196D01*
X1327778Y-441154D01*
X1328215Y-439696D01*
X1329088Y-438821D01*
X1330398Y-438530D01*
X1331708Y-438821D01*
X1333018Y-439696D01*
G01X1347898Y-438530D02*
Y-450196D01*
G01Y-433863D02*
X1347461Y-433571D01*
Y-432988D01*
X1347898Y-432696D01*
X1348335Y-432988D01*
Y-433571D01*
X1347898Y-433863D01*
G01X1362341Y-454571D02*
X1363870Y-455738D01*
X1365616Y-456029D01*
X1367144Y-455738D01*
X1368455Y-454280D01*
X1369328Y-452238D01*
Y-438530D01*
G01Y-440863D02*
X1368455Y-439696D01*
X1367144Y-438821D01*
X1365616Y-438530D01*
X1363870Y-439113D01*
X1362778Y-440279D01*
X1361904Y-442321D01*
X1361468Y-444363D01*
X1361686Y-446113D01*
X1362560Y-448155D01*
X1363870Y-449613D01*
X1365616Y-450196D01*
X1366926Y-449904D01*
X1368455Y-448738D01*
X1369328Y-447572D01*
G01X1379186Y-450196D02*
Y-438530D01*
G01Y-441446D02*
X1380060Y-439988D01*
X1381370Y-438821D01*
X1383116Y-438530D01*
X1384644Y-438821D01*
X1385955Y-439988D01*
X1386610Y-442029D01*
Y-450196D01*
G01X1397123Y-442321D02*
X1404110D01*
X1403455Y-440279D01*
X1402363Y-439113D01*
X1400835Y-438530D01*
X1399306Y-438821D01*
X1397996Y-439696D01*
X1397123Y-441738D01*
X1396686Y-443488D01*
Y-445238D01*
X1397123Y-446988D01*
X1398215Y-448738D01*
X1399525Y-449904D01*
X1401053Y-450196D01*
X1402581Y-449613D01*
X1404110Y-447863D01*
G01X1414841Y-450196D02*
Y-438530D01*
G01Y-440863D02*
X1415933Y-439696D01*
X1417025Y-438821D01*
X1418553Y-438530D01*
X1419644Y-438821D01*
X1420955Y-439696D01*
G01X1461598Y-477696D02*
X1459851Y-478279D01*
X1458541Y-479738D01*
X1457668Y-481487D01*
X1457013Y-483821D01*
X1456795Y-486446D01*
X1457013Y-489071D01*
X1457668Y-491405D01*
X1458541Y-493155D01*
X1459851Y-494613D01*
X1461598Y-495196D01*
X1463344Y-494613D01*
X1464655Y-493155D01*
X1465528Y-491405D01*
X1466183Y-489071D01*
X1466401Y-486446D01*
X1466183Y-483821D01*
X1465528Y-481487D01*
X1464655Y-479738D01*
X1463344Y-478279D01*
X1461598Y-477696D01*
G01X1474950Y-487905D02*
X1476478Y-485863D01*
X1477788Y-484696D01*
X1479535Y-484113D01*
X1481063Y-484696D01*
X1482155Y-485863D01*
X1483028Y-487613D01*
X1483246Y-489654D01*
X1483028Y-491405D01*
X1482155Y-493155D01*
X1480844Y-494613D01*
X1479316Y-495196D01*
X1477570Y-494613D01*
X1476041Y-492863D01*
X1475168Y-490238D01*
X1474950Y-487321D01*
X1475386Y-483530D01*
X1476041Y-481487D01*
X1477133Y-479446D01*
X1478661Y-477988D01*
X1480190Y-477696D01*
X1481718Y-478279D01*
X1482810Y-479738D01*
G01X1492668Y-495779D02*
X1500528Y-477696D01*
G01X1514098D02*
X1512351Y-478279D01*
X1511041Y-479738D01*
X1510168Y-481487D01*
X1509513Y-483821D01*
X1509295Y-486446D01*
X1509513Y-489071D01*
X1510168Y-491405D01*
X1511041Y-493155D01*
X1512351Y-494613D01*
X1514098Y-495196D01*
X1515844Y-494613D01*
X1517155Y-493155D01*
X1518028Y-491405D01*
X1518683Y-489071D01*
X1518901Y-486446D01*
X1518683Y-483821D01*
X1518028Y-481487D01*
X1517155Y-479738D01*
X1515844Y-478279D01*
X1514098Y-477696D01*
G01X1527886Y-493155D02*
X1529415Y-494613D01*
X1531161Y-495196D01*
X1532908Y-494613D01*
X1534436Y-492863D01*
X1535528Y-490238D01*
X1535965Y-487613D01*
Y-484405D01*
X1535528Y-481780D01*
X1534436Y-479446D01*
X1533126Y-478279D01*
X1531598Y-477696D01*
X1529851Y-478279D01*
X1528541Y-479446D01*
X1527668Y-481196D01*
X1527231Y-483530D01*
X1527668Y-485571D01*
X1528760Y-487613D01*
X1530070Y-488780D01*
X1531598Y-489071D01*
X1533344Y-488488D01*
X1534655Y-487029D01*
X1535965Y-484405D01*
G01X1545168Y-495779D02*
X1553028Y-477696D01*
G01X1562450Y-480613D02*
X1563760Y-478863D01*
X1565288Y-477988D01*
X1567035Y-477696D01*
X1569218Y-478279D01*
X1570746Y-479738D01*
X1571183Y-481487D01*
X1570965Y-483238D01*
X1570091Y-484696D01*
X1565725Y-487613D01*
X1563760Y-489654D01*
X1562450Y-492572D01*
X1562013Y-495196D01*
X1571183D01*
G01X1584098Y-477696D02*
X1582351Y-478279D01*
X1581041Y-479738D01*
X1580168Y-481487D01*
X1579513Y-483821D01*
X1579295Y-486446D01*
X1579513Y-489071D01*
X1580168Y-491405D01*
X1581041Y-493155D01*
X1582351Y-494613D01*
X1584098Y-495196D01*
X1585844Y-494613D01*
X1587155Y-493155D01*
X1588028Y-491405D01*
X1588683Y-489071D01*
X1588901Y-486446D01*
X1588683Y-483821D01*
X1588028Y-481487D01*
X1587155Y-479738D01*
X1585844Y-478279D01*
X1584098Y-477696D01*
G01X1601598Y-495196D02*
Y-477696D01*
X1598978Y-481196D01*
G01Y-495196D02*
X1604218D01*
G01X1618661D02*
X1619098Y-491405D01*
X1619753Y-488196D01*
X1620626Y-485279D01*
X1621718Y-482071D01*
X1623465Y-477696D01*
X1614731D01*
G01X1509295Y-450196D02*
Y-432696D01*
X1513661D01*
X1515408Y-433571D01*
X1516718Y-434738D01*
X1517810Y-436487D01*
X1518683Y-438530D01*
X1518901Y-441446D01*
X1518683Y-444363D01*
X1517810Y-446405D01*
X1516718Y-448155D01*
X1515408Y-449321D01*
X1513661Y-450196D01*
X1509295D01*
G01X1535528D02*
Y-438530D01*
G01Y-440571D02*
X1534655Y-439405D01*
X1533344Y-438821D01*
X1531816Y-438530D01*
X1530288Y-439113D01*
X1528978Y-440279D01*
X1528104Y-442029D01*
X1527668Y-444363D01*
X1528104Y-446696D01*
X1528978Y-448446D01*
X1530288Y-449613D01*
X1531816Y-450196D01*
X1533344Y-449904D01*
X1534655Y-449030D01*
X1535528Y-447863D01*
G01X1549098Y-432696D02*
Y-450196D01*
G01X1546041Y-438530D02*
X1552155D01*
G01X1563323Y-442321D02*
X1570310D01*
X1569655Y-440279D01*
X1568563Y-439113D01*
X1567035Y-438530D01*
X1565506Y-438821D01*
X1564196Y-439696D01*
X1563323Y-441738D01*
X1562886Y-443488D01*
Y-445238D01*
X1563323Y-446988D01*
X1564415Y-448738D01*
X1565725Y-449904D01*
X1567253Y-450196D01*
X1568781Y-449613D01*
X1570310Y-447863D01*
G01X2384886Y1473814D02*
X2388606D01*
G01X2386746D02*
Y1461314D01*
G01X2384886D02*
X2388606D01*
G01X2395581D02*
Y1473814D01*
X2402711Y1461314D01*
Y1473814D01*
G01X2411546D02*
Y1461314D01*
G01X2407981Y1473814D02*
X2415111D01*
G01X2423946Y1461314D02*
X2422706Y1461522D01*
X2421621Y1462355D01*
X2420691Y1463606D01*
X2420071Y1465064D01*
X2419761Y1466731D01*
Y1468397D01*
X2420071Y1470064D01*
X2420691Y1471522D01*
X2421621Y1472772D01*
X2422706Y1473606D01*
X2423946Y1473814D01*
X2425186Y1473606D01*
X2426271Y1472772D01*
X2427201Y1471522D01*
X2427821Y1470064D01*
X2428131Y1468397D01*
Y1466731D01*
X2427821Y1465064D01*
X2427201Y1463606D01*
X2426271Y1462355D01*
X2425186Y1461522D01*
X2423946Y1461314D01*
G01X2444871D02*
X2448746Y1473814D01*
X2452621Y1461314D01*
G01X2451226Y1465689D02*
X2446266D01*
G01X2457736Y1461314D02*
Y1473814D01*
X2460836D01*
X2462076Y1473189D01*
X2463006Y1472356D01*
X2463781Y1471106D01*
X2464401Y1469647D01*
X2464556Y1467564D01*
X2464401Y1465481D01*
X2463781Y1464022D01*
X2463006Y1462772D01*
X2462076Y1461939D01*
X2460836Y1461314D01*
X2457736D01*
G01X2470446Y1463814D02*
X2471221Y1462564D01*
X2472151Y1461731D01*
X2473236Y1461314D01*
X2474476Y1461731D01*
X2475406Y1462564D01*
X2476336Y1463814D01*
X2476646Y1465481D01*
Y1473814D01*
G01X2482071Y1461314D02*
X2485946Y1473814D01*
X2489821Y1461314D01*
G01X2488426Y1465689D02*
X2483466D01*
G01X2501756Y1472772D02*
X2500826Y1473397D01*
X2499741Y1473814D01*
X2498501D01*
X2497106Y1473189D01*
X2496021Y1472147D01*
X2495246Y1470897D01*
X2494626Y1468814D01*
X2494471Y1466939D01*
X2494781Y1465064D01*
X2495246Y1463814D01*
X2496176Y1462564D01*
X2497261Y1461731D01*
X2498346Y1461314D01*
X2499431D01*
X2500516Y1461731D01*
X2501446Y1462355D01*
X2502221Y1463189D01*
G01X2513846Y1461314D02*
X2507646D01*
Y1473814D01*
X2513846D01*
G01X2511366Y1467772D02*
X2507646D01*
G01X2519581Y1461314D02*
Y1473814D01*
X2526711Y1461314D01*
Y1473814D01*
G01X2535546D02*
Y1461314D01*
G01X2531981Y1473814D02*
X2539111D01*
G01X2556936Y1461314D02*
Y1473814D01*
X2560036D01*
X2561276Y1473189D01*
X2562206Y1472356D01*
X2562981Y1471106D01*
X2563601Y1469647D01*
X2563756Y1467564D01*
X2563601Y1465481D01*
X2562981Y1464022D01*
X2562206Y1462772D01*
X2561276Y1461939D01*
X2560036Y1461314D01*
X2556936D01*
G01X2570886Y1473814D02*
X2574606D01*
G01X2572746D02*
Y1461314D01*
G01X2570886D02*
X2574606D01*
G01X2588246D02*
X2582046D01*
Y1473814D01*
X2588246D01*
G01X2585766Y1467772D02*
X2582046D01*
G01X2594446Y1473814D02*
Y1461314D01*
X2600646D01*
G01X2613046D02*
X2606846D01*
Y1473814D01*
X2613046D01*
G01X2610566Y1467772D02*
X2606846D01*
G01X2625756Y1472772D02*
X2624826Y1473397D01*
X2623741Y1473814D01*
X2622501D01*
X2621106Y1473189D01*
X2620021Y1472147D01*
X2619246Y1470897D01*
X2618626Y1468814D01*
X2618471Y1466939D01*
X2618781Y1465064D01*
X2619246Y1463814D01*
X2620176Y1462564D01*
X2621261Y1461731D01*
X2622346Y1461314D01*
X2623431D01*
X2624516Y1461731D01*
X2625446Y1462355D01*
X2626221Y1463189D01*
G01X2634746Y1473814D02*
Y1461314D01*
G01X2631181Y1473814D02*
X2638311D01*
G01X2644046Y1461314D02*
Y1473814D01*
X2647921D01*
X2649161Y1473189D01*
X2649936Y1472356D01*
X2650246Y1470689D01*
X2649936Y1469022D01*
X2649006Y1467981D01*
X2647921Y1467356D01*
X2644046D01*
G01X2647921D02*
X2650246Y1461314D01*
G01X2657686Y1473814D02*
X2661406D01*
G01X2659546D02*
Y1461314D01*
G01X2657686D02*
X2661406D01*
G01X2675356Y1472772D02*
X2674426Y1473397D01*
X2673341Y1473814D01*
X2672101D01*
X2670706Y1473189D01*
X2669621Y1472147D01*
X2668846Y1470897D01*
X2668226Y1468814D01*
X2668071Y1466939D01*
X2668381Y1465064D01*
X2668846Y1463814D01*
X2669776Y1462564D01*
X2670861Y1461731D01*
X2671946Y1461314D01*
X2673031D01*
X2674116Y1461731D01*
X2675046Y1462355D01*
X2675821Y1463189D01*
G01X2693646Y1473814D02*
Y1461314D01*
X2699846D01*
G01X2705271D02*
X2709146Y1473814D01*
X2713021Y1461314D01*
G01X2711626Y1465689D02*
X2706666D01*
G01X2721546Y1461314D02*
Y1466939D01*
X2718446Y1473814D01*
G01X2724646D02*
X2721546Y1466939D01*
G01X2737046Y1461314D02*
X2730846D01*
Y1473814D01*
X2737046D01*
G01X2734566Y1467772D02*
X2730846D01*
G01X2743246Y1461314D02*
Y1473814D01*
X2747121D01*
X2748361Y1473189D01*
X2749136Y1472356D01*
X2749446Y1470689D01*
X2749136Y1469022D01*
X2748206Y1467981D01*
X2747121Y1467356D01*
X2743246D01*
G01X2747121D02*
X2749446Y1461314D01*
G01X2758746Y1460897D02*
X2758436Y1461106D01*
Y1461522D01*
X2758746Y1461731D01*
X2759056Y1461522D01*
Y1461106D01*
X2758746Y1460897D01*
G01X2386746Y1530014D02*
Y1517514D01*
G01X2383181Y1530014D02*
X2390311D01*
G01X2399146Y1517514D02*
X2397906Y1517722D01*
X2396821Y1518555D01*
X2395891Y1519806D01*
X2395271Y1521264D01*
X2394961Y1522931D01*
Y1524597D01*
X2395271Y1526264D01*
X2395891Y1527722D01*
X2396821Y1528972D01*
X2397906Y1529806D01*
X2399146Y1530014D01*
X2400386Y1529806D01*
X2401471Y1528972D01*
X2402401Y1527722D01*
X2403021Y1526264D01*
X2403331Y1524597D01*
Y1522931D01*
X2403021Y1521264D01*
X2402401Y1519806D01*
X2401471Y1518555D01*
X2400386Y1517722D01*
X2399146Y1517514D01*
G01X2411546D02*
X2410306Y1517722D01*
X2409221Y1518555D01*
X2408291Y1519806D01*
X2407671Y1521264D01*
X2407361Y1522931D01*
Y1524597D01*
X2407671Y1526264D01*
X2408291Y1527722D01*
X2409221Y1528972D01*
X2410306Y1529806D01*
X2411546Y1530014D01*
X2412786Y1529806D01*
X2413871Y1528972D01*
X2414801Y1527722D01*
X2415421Y1526264D01*
X2415731Y1524597D01*
Y1522931D01*
X2415421Y1521264D01*
X2414801Y1519806D01*
X2413871Y1518555D01*
X2412786Y1517722D01*
X2411546Y1517514D01*
G01X2420846Y1530014D02*
Y1517514D01*
X2427046D01*
G01X2434486Y1530014D02*
X2438206D01*
G01X2436346D02*
Y1517514D01*
G01X2434486D02*
X2438206D01*
G01X2445181D02*
Y1530014D01*
X2452311Y1517514D01*
Y1530014D01*
G01X2462076Y1523764D02*
X2465176D01*
Y1520014D01*
X2464246Y1518764D01*
X2463161Y1517931D01*
X2461611Y1517514D01*
X2460061Y1517931D01*
X2458976Y1518764D01*
X2458046Y1520014D01*
X2457426Y1521472D01*
X2457116Y1523139D01*
Y1524597D01*
X2457426Y1525847D01*
X2458046Y1527306D01*
X2458976Y1528556D01*
X2459906Y1529389D01*
X2461146Y1530014D01*
X2462231D01*
X2463471Y1529597D01*
X2464401Y1528764D01*
G01X2483001Y1517514D02*
Y1530014D01*
X2488891D01*
G01X2486721Y1523972D02*
X2483001D01*
G01X2498346Y1517514D02*
X2497106Y1517722D01*
X2496021Y1518555D01*
X2495091Y1519806D01*
X2494471Y1521264D01*
X2494161Y1522931D01*
Y1524597D01*
X2494471Y1526264D01*
X2495091Y1527722D01*
X2496021Y1528972D01*
X2497106Y1529806D01*
X2498346Y1530014D01*
X2499586Y1529806D01*
X2500671Y1528972D01*
X2501601Y1527722D01*
X2502221Y1526264D01*
X2502531Y1524597D01*
Y1522931D01*
X2502221Y1521264D01*
X2501601Y1519806D01*
X2500671Y1518555D01*
X2499586Y1517722D01*
X2498346Y1517514D01*
G01X2507646D02*
Y1530014D01*
X2511521D01*
X2512761Y1529389D01*
X2513536Y1528556D01*
X2513846Y1526889D01*
X2513536Y1525222D01*
X2512606Y1524181D01*
X2511521Y1523556D01*
X2507646D01*
G01X2511521D02*
X2513846Y1517514D01*
G01X2535546D02*
X2534306Y1517722D01*
X2533221Y1518555D01*
X2532291Y1519806D01*
X2531671Y1521264D01*
X2531361Y1522931D01*
Y1524597D01*
X2531671Y1526264D01*
X2532291Y1527722D01*
X2533221Y1528972D01*
X2534306Y1529806D01*
X2535546Y1530014D01*
X2536786Y1529806D01*
X2537871Y1528972D01*
X2538801Y1527722D01*
X2539421Y1526264D01*
X2539731Y1524597D01*
Y1522931D01*
X2539421Y1521264D01*
X2538801Y1519806D01*
X2537871Y1518555D01*
X2536786Y1517722D01*
X2535546Y1517514D01*
G01X2544071Y1530014D02*
X2547946Y1517514D01*
X2551821Y1530014D01*
G01X2563446Y1517514D02*
X2557246D01*
Y1530014D01*
X2563446D01*
G01X2560966Y1523972D02*
X2557246D01*
G01X2569646Y1517514D02*
Y1530014D01*
X2573521D01*
X2574761Y1529389D01*
X2575536Y1528556D01*
X2575846Y1526889D01*
X2575536Y1525222D01*
X2574606Y1524181D01*
X2573521Y1523556D01*
X2569646D01*
G01X2573521D02*
X2575846Y1517514D01*
G01X2581736D02*
Y1530014D01*
X2584836D01*
X2586076Y1529389D01*
X2587006Y1528556D01*
X2587781Y1527306D01*
X2588401Y1525847D01*
X2588556Y1523764D01*
X2588401Y1521681D01*
X2587781Y1520222D01*
X2587006Y1518972D01*
X2586076Y1518139D01*
X2584836Y1517514D01*
X2581736D01*
G01X2594446D02*
Y1530014D01*
X2598321D01*
X2599561Y1529389D01*
X2600336Y1528556D01*
X2600646Y1526889D01*
X2600336Y1525222D01*
X2599406Y1524181D01*
X2598321Y1523556D01*
X2594446D01*
G01X2598321D02*
X2600646Y1517514D01*
G01X2608086Y1530014D02*
X2611806D01*
G01X2609946D02*
Y1517514D01*
G01X2608086D02*
X2611806D01*
G01X2619246Y1530014D02*
Y1517514D01*
X2625446D01*
G01X2631646Y1530014D02*
Y1517514D01*
X2637846D01*
G01X2645286Y1530014D02*
X2649006D01*
G01X2647146D02*
Y1517514D01*
G01X2645286D02*
X2649006D01*
G01X2655981D02*
Y1530014D01*
X2663111Y1517514D01*
Y1530014D01*
G01X2672876Y1523764D02*
X2675976D01*
Y1520014D01*
X2675046Y1518764D01*
X2673961Y1517931D01*
X2672411Y1517514D01*
X2670861Y1517931D01*
X2669776Y1518764D01*
X2668846Y1520014D01*
X2668226Y1521472D01*
X2667916Y1523139D01*
Y1524597D01*
X2668226Y1525847D01*
X2668846Y1527306D01*
X2669776Y1528556D01*
X2670706Y1529389D01*
X2671946Y1530014D01*
X2673031D01*
X2674271Y1529597D01*
X2675201Y1528764D01*
G01X2684346Y1517097D02*
X2684036Y1517306D01*
Y1517722D01*
X2684346Y1517931D01*
X2684656Y1517722D01*
Y1517306D01*
X2684346Y1517097D01*
G01X2359931Y1493581D02*
X2363961D01*
G01X2383646Y1501914D02*
Y1489414D01*
X2389846D01*
G01X2402246D02*
X2396046D01*
Y1501914D01*
X2402246D01*
G01X2399766Y1495872D02*
X2396046D01*
G01X2412476Y1495664D02*
X2415576D01*
Y1491914D01*
X2414646Y1490664D01*
X2413561Y1489831D01*
X2412011Y1489414D01*
X2410461Y1489831D01*
X2409376Y1490664D01*
X2408446Y1491914D01*
X2407826Y1493372D01*
X2407516Y1495039D01*
Y1496497D01*
X2407826Y1497747D01*
X2408446Y1499206D01*
X2409376Y1500456D01*
X2410306Y1501289D01*
X2411546Y1501914D01*
X2412631D01*
X2413871Y1501497D01*
X2414801Y1500664D01*
G01X2427046Y1489414D02*
X2420846D01*
Y1501914D01*
X2427046D01*
G01X2424566Y1495872D02*
X2420846D01*
G01X2432781Y1489414D02*
Y1501914D01*
X2439911Y1489414D01*
Y1501914D01*
G01X2445336Y1489414D02*
Y1501914D01*
X2448436D01*
X2449676Y1501289D01*
X2450606Y1500456D01*
X2451381Y1499206D01*
X2452001Y1497747D01*
X2452156Y1495664D01*
X2452001Y1493581D01*
X2451381Y1492122D01*
X2450606Y1490872D01*
X2449676Y1490039D01*
X2448436Y1489414D01*
X2445336D01*
G01X2470136D02*
Y1501914D01*
X2473236D01*
X2474476Y1501289D01*
X2475406Y1500456D01*
X2476181Y1499206D01*
X2476801Y1497747D01*
X2476956Y1495664D01*
X2476801Y1493581D01*
X2476181Y1492122D01*
X2475406Y1490872D01*
X2474476Y1490039D01*
X2473236Y1489414D01*
X2470136D01*
G01X2485946D02*
X2484706Y1489622D01*
X2483621Y1490455D01*
X2482691Y1491706D01*
X2482071Y1493164D01*
X2481761Y1494831D01*
Y1496497D01*
X2482071Y1498164D01*
X2482691Y1499622D01*
X2483621Y1500872D01*
X2484706Y1501706D01*
X2485946Y1501914D01*
X2487186Y1501706D01*
X2488271Y1500872D01*
X2489201Y1499622D01*
X2489821Y1498164D01*
X2490131Y1496497D01*
Y1494831D01*
X2489821Y1493164D01*
X2489201Y1491706D01*
X2488271Y1490455D01*
X2487186Y1489622D01*
X2485946Y1489414D01*
G01X2501446D02*
X2495246D01*
Y1501914D01*
X2501446D01*
G01X2498966Y1495872D02*
X2495246D01*
G01X2507491Y1491080D02*
X2508731Y1490039D01*
X2510126Y1489414D01*
X2511366D01*
X2512606Y1490039D01*
X2513536Y1491080D01*
X2514001Y1492539D01*
X2513691Y1493997D01*
X2512916Y1495247D01*
X2511521Y1496081D01*
X2509661Y1496497D01*
X2508576Y1497331D01*
X2508111Y1498789D01*
X2508421Y1500247D01*
X2509196Y1501289D01*
X2510281Y1501914D01*
X2511366D01*
X2512451Y1501497D01*
X2513381Y1500456D01*
G01X2531981Y1489414D02*
Y1501914D01*
X2539111Y1489414D01*
Y1501914D01*
G01X2547946Y1489414D02*
X2546706Y1489622D01*
X2545621Y1490455D01*
X2544691Y1491706D01*
X2544071Y1493164D01*
X2543761Y1494831D01*
Y1496497D01*
X2544071Y1498164D01*
X2544691Y1499622D01*
X2545621Y1500872D01*
X2546706Y1501706D01*
X2547946Y1501914D01*
X2549186Y1501706D01*
X2550271Y1500872D01*
X2551201Y1499622D01*
X2551821Y1498164D01*
X2552131Y1496497D01*
Y1494831D01*
X2551821Y1493164D01*
X2551201Y1491706D01*
X2550271Y1490455D01*
X2549186Y1489622D01*
X2547946Y1489414D01*
G01X2560346Y1501914D02*
Y1489414D01*
G01X2556781Y1501914D02*
X2563911D01*
G01X2581891Y1491080D02*
X2583131Y1490039D01*
X2584526Y1489414D01*
X2585766D01*
X2587006Y1490039D01*
X2587936Y1491080D01*
X2588401Y1492539D01*
X2588091Y1493997D01*
X2587316Y1495247D01*
X2585921Y1496081D01*
X2584061Y1496497D01*
X2582976Y1497331D01*
X2582511Y1498789D01*
X2582821Y1500247D01*
X2583596Y1501289D01*
X2584681Y1501914D01*
X2585766D01*
X2586851Y1501497D01*
X2587781Y1500456D01*
G01X2594446Y1489414D02*
Y1501914D01*
X2598166D01*
X2599406Y1501289D01*
X2600336Y1499831D01*
X2600646Y1498164D01*
X2600336Y1496497D01*
X2599561Y1495247D01*
X2598166Y1494622D01*
X2594446D01*
G01X2613046Y1489414D02*
X2606846D01*
Y1501914D01*
X2613046D01*
G01X2610566Y1495872D02*
X2606846D01*
G01X2625756Y1500872D02*
X2624826Y1501497D01*
X2623741Y1501914D01*
X2622501D01*
X2621106Y1501289D01*
X2620021Y1500247D01*
X2619246Y1498997D01*
X2618626Y1496914D01*
X2618471Y1495039D01*
X2618781Y1493164D01*
X2619246Y1491914D01*
X2620176Y1490664D01*
X2621261Y1489831D01*
X2622346Y1489414D01*
X2623431D01*
X2624516Y1489831D01*
X2625446Y1490455D01*
X2626221Y1491289D01*
G01X2632886Y1501914D02*
X2636606D01*
G01X2634746D02*
Y1489414D01*
G01X2632886D02*
X2636606D01*
G01X2644201D02*
Y1501914D01*
X2650091D01*
G01X2647921Y1495872D02*
X2644201D01*
G01X2659546Y1489414D02*
Y1495039D01*
X2656446Y1501914D01*
G01X2662646D02*
X2659546Y1495039D01*
G01X2680936Y1489414D02*
Y1501914D01*
X2684036D01*
X2685276Y1501289D01*
X2686206Y1500456D01*
X2686981Y1499206D01*
X2687601Y1497747D01*
X2687756Y1495664D01*
X2687601Y1493581D01*
X2686981Y1492122D01*
X2686206Y1490872D01*
X2685276Y1490039D01*
X2684036Y1489414D01*
X2680936D01*
G01X2699846D02*
X2693646D01*
Y1501914D01*
X2699846D01*
G01X2697366Y1495872D02*
X2693646D01*
G01X2706046Y1489414D02*
Y1501914D01*
X2709766D01*
X2711006Y1501289D01*
X2711936Y1499831D01*
X2712246Y1498164D01*
X2711936Y1496497D01*
X2711161Y1495247D01*
X2709766Y1494622D01*
X2706046D01*
G01X2721546Y1501914D02*
Y1489414D01*
G01X2717981Y1501914D02*
X2725111D01*
G01X2730691Y1489414D02*
Y1501914D01*
G01X2737201D02*
Y1489414D01*
G01Y1495664D02*
X2730691D01*
G01X2359931Y1549781D02*
X2363961D01*
G01X2382871Y1558114D02*
X2386746Y1545614D01*
X2390621Y1558114D01*
G01X2402246Y1545614D02*
X2396046D01*
Y1558114D01*
X2402246D01*
G01X2399766Y1552072D02*
X2396046D01*
G01X2407981Y1545614D02*
Y1558114D01*
X2415111Y1545614D01*
Y1558114D01*
G01X2420536Y1545614D02*
Y1558114D01*
X2423636D01*
X2424876Y1557489D01*
X2425806Y1556656D01*
X2426581Y1555406D01*
X2427201Y1553947D01*
X2427356Y1551864D01*
X2427201Y1549781D01*
X2426581Y1548322D01*
X2425806Y1547072D01*
X2424876Y1546239D01*
X2423636Y1545614D01*
X2420536D01*
G01X2436346D02*
X2435106Y1545822D01*
X2434021Y1546655D01*
X2433091Y1547906D01*
X2432471Y1549364D01*
X2432161Y1551031D01*
Y1552697D01*
X2432471Y1554364D01*
X2433091Y1555822D01*
X2434021Y1557072D01*
X2435106Y1557906D01*
X2436346Y1558114D01*
X2437586Y1557906D01*
X2438671Y1557072D01*
X2439601Y1555822D01*
X2440221Y1554364D01*
X2440531Y1552697D01*
Y1551031D01*
X2440221Y1549364D01*
X2439601Y1547906D01*
X2438671Y1546655D01*
X2437586Y1545822D01*
X2436346Y1545614D01*
G01X2445646D02*
Y1558114D01*
X2449521D01*
X2450761Y1557489D01*
X2451536Y1556656D01*
X2451846Y1554989D01*
X2451536Y1553322D01*
X2450606Y1552281D01*
X2449521Y1551656D01*
X2445646D01*
G01X2449521D02*
X2451846Y1545614D01*
G01X2471686Y1558114D02*
X2475406D01*
G01X2473546D02*
Y1545614D01*
G01X2471686D02*
X2475406D01*
G01X2482691Y1547280D02*
X2483931Y1546239D01*
X2485326Y1545614D01*
X2486566D01*
X2487806Y1546239D01*
X2488736Y1547280D01*
X2489201Y1548739D01*
X2488891Y1550197D01*
X2488116Y1551447D01*
X2486721Y1552281D01*
X2484861Y1552697D01*
X2483776Y1553531D01*
X2483311Y1554989D01*
X2483621Y1556447D01*
X2484396Y1557489D01*
X2485481Y1558114D01*
X2486566D01*
X2487651Y1557697D01*
X2488581Y1556656D01*
G01X2507646Y1545614D02*
Y1558114D01*
X2511521D01*
X2512761Y1557489D01*
X2513536Y1556656D01*
X2513846Y1554989D01*
X2513536Y1553322D01*
X2512606Y1552281D01*
X2511521Y1551656D01*
X2507646D01*
G01X2511521D02*
X2513846Y1545614D01*
G01X2526246D02*
X2520046D01*
Y1558114D01*
X2526246D01*
G01X2523766Y1552072D02*
X2520046D01*
G01X2535546Y1545614D02*
X2534306Y1545822D01*
X2533221Y1546655D01*
X2532291Y1547906D01*
X2531671Y1549364D01*
X2531361Y1551031D01*
Y1552697D01*
X2531671Y1554364D01*
X2532291Y1555822D01*
X2533221Y1557072D01*
X2534306Y1557906D01*
X2535546Y1558114D01*
X2536786Y1557906D01*
X2537871Y1557072D01*
X2538801Y1555822D01*
X2539421Y1554364D01*
X2539731Y1552697D01*
Y1551031D01*
X2539421Y1549364D01*
X2538801Y1547906D01*
X2537871Y1546655D01*
X2536786Y1545822D01*
X2535546Y1545614D01*
G01X2536786Y1548947D02*
X2538646Y1545614D01*
G01X2544536Y1558114D02*
Y1549156D01*
X2545156Y1547280D01*
X2546396Y1546031D01*
X2547946Y1545614D01*
X2549496Y1546031D01*
X2550736Y1547280D01*
X2551356Y1549156D01*
Y1558114D01*
G01X2558486D02*
X2562206D01*
G01X2560346D02*
Y1545614D01*
G01X2558486D02*
X2562206D01*
G01X2569646D02*
Y1558114D01*
X2573521D01*
X2574761Y1557489D01*
X2575536Y1556656D01*
X2575846Y1554989D01*
X2575536Y1553322D01*
X2574606Y1552281D01*
X2573521Y1551656D01*
X2569646D01*
G01X2573521D02*
X2575846Y1545614D01*
G01X2588246D02*
X2582046D01*
Y1558114D01*
X2588246D01*
G01X2585766Y1552072D02*
X2582046D01*
G01X2594136Y1545614D02*
Y1558114D01*
X2597236D01*
X2598476Y1557489D01*
X2599406Y1556656D01*
X2600181Y1555406D01*
X2600801Y1553947D01*
X2600956Y1551864D01*
X2600801Y1549781D01*
X2600181Y1548322D01*
X2599406Y1547072D01*
X2598476Y1546239D01*
X2597236Y1545614D01*
X2594136D01*
G01X2622346Y1558114D02*
Y1545614D01*
G01X2618781Y1558114D02*
X2625911D01*
G01X2634746Y1545614D02*
X2633506Y1545822D01*
X2632421Y1546655D01*
X2631491Y1547906D01*
X2630871Y1549364D01*
X2630561Y1551031D01*
Y1552697D01*
X2630871Y1554364D01*
X2631491Y1555822D01*
X2632421Y1557072D01*
X2633506Y1557906D01*
X2634746Y1558114D01*
X2635986Y1557906D01*
X2637071Y1557072D01*
X2638001Y1555822D01*
X2638621Y1554364D01*
X2638931Y1552697D01*
Y1551031D01*
X2638621Y1549364D01*
X2638001Y1547906D01*
X2637071Y1546655D01*
X2635986Y1545822D01*
X2634746Y1545614D01*
G01X2656291Y1547280D02*
X2657531Y1546239D01*
X2658926Y1545614D01*
X2660166D01*
X2661406Y1546239D01*
X2662336Y1547280D01*
X2662801Y1548739D01*
X2662491Y1550197D01*
X2661716Y1551447D01*
X2660321Y1552281D01*
X2658461Y1552697D01*
X2657376Y1553531D01*
X2656911Y1554989D01*
X2657221Y1556447D01*
X2657996Y1557489D01*
X2659081Y1558114D01*
X2660166D01*
X2661251Y1557697D01*
X2662181Y1556656D01*
G01X2675046Y1545614D02*
X2668846D01*
Y1558114D01*
X2675046D01*
G01X2672566Y1552072D02*
X2668846D01*
G01X2681246Y1558114D02*
Y1545614D01*
X2687446D01*
G01X2699846D02*
X2693646D01*
Y1558114D01*
X2699846D01*
G01X2697366Y1552072D02*
X2693646D01*
G01X2712556Y1557072D02*
X2711626Y1557697D01*
X2710541Y1558114D01*
X2709301D01*
X2707906Y1557489D01*
X2706821Y1556447D01*
X2706046Y1555197D01*
X2705426Y1553114D01*
X2705271Y1551239D01*
X2705581Y1549364D01*
X2706046Y1548114D01*
X2706976Y1546864D01*
X2708061Y1546031D01*
X2709146Y1545614D01*
X2710231D01*
X2711316Y1546031D01*
X2712246Y1546655D01*
X2713021Y1547489D01*
G01X2721546Y1558114D02*
Y1545614D01*
G01X2717981Y1558114D02*
X2725111D01*
G01X2359931Y1605981D02*
X2363961D01*
G01X2383336Y1601814D02*
Y1614314D01*
X2386436D01*
X2387676Y1613689D01*
X2388606Y1612856D01*
X2389381Y1611606D01*
X2390001Y1610147D01*
X2390156Y1608064D01*
X2390001Y1605981D01*
X2389381Y1604522D01*
X2388606Y1603272D01*
X2387676Y1602439D01*
X2386436Y1601814D01*
X2383336D01*
G01X2396046D02*
Y1614314D01*
X2399921D01*
X2401161Y1613689D01*
X2401936Y1612856D01*
X2402246Y1611189D01*
X2401936Y1609522D01*
X2401006Y1608481D01*
X2399921Y1607856D01*
X2396046D01*
G01X2399921D02*
X2402246Y1601814D01*
G01X2409686Y1614314D02*
X2413406D01*
G01X2411546D02*
Y1601814D01*
G01X2409686D02*
X2413406D01*
G01X2420846Y1614314D02*
Y1601814D01*
X2427046D01*
G01X2433246Y1614314D02*
Y1601814D01*
X2439446D01*
G01X2457891Y1603480D02*
X2459131Y1602439D01*
X2460526Y1601814D01*
X2461766D01*
X2463006Y1602439D01*
X2463936Y1603480D01*
X2464401Y1604939D01*
X2464091Y1606397D01*
X2463316Y1607647D01*
X2461921Y1608481D01*
X2460061Y1608897D01*
X2458976Y1609731D01*
X2458511Y1611189D01*
X2458821Y1612647D01*
X2459596Y1613689D01*
X2460681Y1614314D01*
X2461766D01*
X2462851Y1613897D01*
X2463781Y1612856D01*
G01X2471686Y1614314D02*
X2475406D01*
G01X2473546D02*
Y1601814D01*
G01X2471686D02*
X2475406D01*
G01X2483001Y1614314D02*
X2488891D01*
X2483001Y1601814D01*
X2488891D01*
G01X2501446D02*
X2495246D01*
Y1614314D01*
X2501446D01*
G01X2498966Y1608272D02*
X2495246D01*
G01X2507491Y1603480D02*
X2508731Y1602439D01*
X2510126Y1601814D01*
X2511366D01*
X2512606Y1602439D01*
X2513536Y1603480D01*
X2514001Y1604939D01*
X2513691Y1606397D01*
X2512916Y1607647D01*
X2511521Y1608481D01*
X2509661Y1608897D01*
X2508576Y1609731D01*
X2508111Y1611189D01*
X2508421Y1612647D01*
X2509196Y1613689D01*
X2510281Y1614314D01*
X2511366D01*
X2512451Y1613897D01*
X2513381Y1612856D01*
G01X2532446Y1614314D02*
Y1601814D01*
X2538646D01*
G01X2546086Y1614314D02*
X2549806D01*
G01X2547946D02*
Y1601814D01*
G01X2546086D02*
X2549806D01*
G01X2557091Y1603480D02*
X2558331Y1602439D01*
X2559726Y1601814D01*
X2560966D01*
X2562206Y1602439D01*
X2563136Y1603480D01*
X2563601Y1604939D01*
X2563291Y1606397D01*
X2562516Y1607647D01*
X2561121Y1608481D01*
X2559261Y1608897D01*
X2558176Y1609731D01*
X2557711Y1611189D01*
X2558021Y1612647D01*
X2558796Y1613689D01*
X2559881Y1614314D01*
X2560966D01*
X2562051Y1613897D01*
X2562981Y1612856D01*
G01X2572746Y1614314D02*
Y1601814D01*
G01X2569181Y1614314D02*
X2576311D01*
G01X2588246Y1601814D02*
X2582046D01*
Y1614314D01*
X2588246D01*
G01X2585766Y1608272D02*
X2582046D01*
G01X2594136Y1601814D02*
Y1614314D01*
X2597236D01*
X2598476Y1613689D01*
X2599406Y1612856D01*
X2600181Y1611606D01*
X2600801Y1610147D01*
X2600956Y1608064D01*
X2600801Y1605981D01*
X2600181Y1604522D01*
X2599406Y1603272D01*
X2598476Y1602439D01*
X2597236Y1601814D01*
X2594136D01*
G01X2620486Y1614314D02*
X2624206D01*
G01X2622346D02*
Y1601814D01*
G01X2620486D02*
X2624206D01*
G01X2631181D02*
Y1614314D01*
X2638311Y1601814D01*
Y1614314D01*
G01X2656446D02*
Y1601814D01*
X2662646D01*
G01X2675046D02*
X2668846D01*
Y1614314D01*
X2675046D01*
G01X2672566Y1608272D02*
X2668846D01*
G01X2685276Y1608064D02*
X2688376D01*
Y1604314D01*
X2687446Y1603064D01*
X2686361Y1602231D01*
X2684811Y1601814D01*
X2683261Y1602231D01*
X2682176Y1603064D01*
X2681246Y1604314D01*
X2680626Y1605772D01*
X2680316Y1607439D01*
Y1608897D01*
X2680626Y1610147D01*
X2681246Y1611606D01*
X2682176Y1612856D01*
X2683106Y1613689D01*
X2684346Y1614314D01*
X2685431D01*
X2686671Y1613897D01*
X2687601Y1613064D01*
G01X2699846Y1601814D02*
X2693646D01*
Y1614314D01*
X2699846D01*
G01X2697366Y1608272D02*
X2693646D01*
G01X2705581Y1601814D02*
Y1614314D01*
X2712711Y1601814D01*
Y1614314D01*
G01X2718136Y1601814D02*
Y1614314D01*
X2721236D01*
X2722476Y1613689D01*
X2723406Y1612856D01*
X2724181Y1611606D01*
X2724801Y1610147D01*
X2724956Y1608064D01*
X2724801Y1605981D01*
X2724181Y1604522D01*
X2723406Y1603272D01*
X2722476Y1602439D01*
X2721236Y1601814D01*
X2718136D01*
G01X2382871Y1573714D02*
X2386746Y1586214D01*
X2390621Y1573714D01*
G01X2389226Y1578089D02*
X2384266D01*
G01X2396046Y1573714D02*
Y1586214D01*
X2399921D01*
X2401161Y1585589D01*
X2401936Y1584756D01*
X2402246Y1583089D01*
X2401936Y1581422D01*
X2401006Y1580381D01*
X2399921Y1579756D01*
X2396046D01*
G01X2399921D02*
X2402246Y1573714D01*
G01X2414646D02*
X2408446D01*
Y1586214D01*
X2414646D01*
G01X2412166Y1580172D02*
X2408446D01*
G01X2439756Y1585172D02*
X2438826Y1585797D01*
X2437741Y1586214D01*
X2436501D01*
X2435106Y1585589D01*
X2434021Y1584547D01*
X2433246Y1583297D01*
X2432626Y1581214D01*
X2432471Y1579339D01*
X2432781Y1577464D01*
X2433246Y1576214D01*
X2434176Y1574964D01*
X2435261Y1574131D01*
X2436346Y1573714D01*
X2437431D01*
X2438516Y1574131D01*
X2439446Y1574755D01*
X2440221Y1575589D01*
G01X2448746Y1573714D02*
X2447506Y1573922D01*
X2446421Y1574755D01*
X2445491Y1576006D01*
X2444871Y1577464D01*
X2444561Y1579131D01*
Y1580797D01*
X2444871Y1582464D01*
X2445491Y1583922D01*
X2446421Y1585172D01*
X2447506Y1586006D01*
X2448746Y1586214D01*
X2449986Y1586006D01*
X2451071Y1585172D01*
X2452001Y1583922D01*
X2452621Y1582464D01*
X2452931Y1580797D01*
Y1579131D01*
X2452621Y1577464D01*
X2452001Y1576006D01*
X2451071Y1574755D01*
X2449986Y1573922D01*
X2448746Y1573714D01*
G01X2457581D02*
Y1586214D01*
X2464711Y1573714D01*
Y1586214D01*
G01X2470291Y1575380D02*
X2471531Y1574339D01*
X2472926Y1573714D01*
X2474166D01*
X2475406Y1574339D01*
X2476336Y1575380D01*
X2476801Y1576839D01*
X2476491Y1578297D01*
X2475716Y1579547D01*
X2474321Y1580381D01*
X2472461Y1580797D01*
X2471376Y1581631D01*
X2470911Y1583089D01*
X2471221Y1584547D01*
X2471996Y1585589D01*
X2473081Y1586214D01*
X2474166D01*
X2475251Y1585797D01*
X2476181Y1584756D01*
G01X2484086Y1586214D02*
X2487806D01*
G01X2485946D02*
Y1573714D01*
G01X2484086D02*
X2487806D01*
G01X2494936D02*
Y1586214D01*
X2498036D01*
X2499276Y1585589D01*
X2500206Y1584756D01*
X2500981Y1583506D01*
X2501601Y1582047D01*
X2501756Y1579964D01*
X2501601Y1577881D01*
X2500981Y1576422D01*
X2500206Y1575172D01*
X2499276Y1574339D01*
X2498036Y1573714D01*
X2494936D01*
G01X2513846D02*
X2507646D01*
Y1586214D01*
X2513846D01*
G01X2511366Y1580172D02*
X2507646D01*
G01X2520046Y1573714D02*
Y1586214D01*
X2523921D01*
X2525161Y1585589D01*
X2525936Y1584756D01*
X2526246Y1583089D01*
X2525936Y1581422D01*
X2525006Y1580381D01*
X2523921Y1579756D01*
X2520046D01*
G01X2523921D02*
X2526246Y1573714D01*
G01X2538646D02*
X2532446D01*
Y1586214D01*
X2538646D01*
G01X2536166Y1580172D02*
X2532446D01*
G01X2544536Y1573714D02*
Y1586214D01*
X2547636D01*
X2548876Y1585589D01*
X2549806Y1584756D01*
X2550581Y1583506D01*
X2551201Y1582047D01*
X2551356Y1579964D01*
X2551201Y1577881D01*
X2550581Y1576422D01*
X2549806Y1575172D01*
X2548876Y1574339D01*
X2547636Y1573714D01*
X2544536D01*
G01X2569801D02*
Y1586214D01*
X2575691D01*
G01X2573521Y1580172D02*
X2569801D01*
G01X2583286Y1586214D02*
X2587006D01*
G01X2585146D02*
Y1573714D01*
G01X2583286D02*
X2587006D01*
G01X2593981D02*
Y1586214D01*
X2601111Y1573714D01*
Y1586214D01*
G01X2608086D02*
X2611806D01*
G01X2609946D02*
Y1573714D01*
G01X2608086D02*
X2611806D01*
G01X2619091Y1575380D02*
X2620331Y1574339D01*
X2621726Y1573714D01*
X2622966D01*
X2624206Y1574339D01*
X2625136Y1575380D01*
X2625601Y1576839D01*
X2625291Y1578297D01*
X2624516Y1579547D01*
X2623121Y1580381D01*
X2621261Y1580797D01*
X2620176Y1581631D01*
X2619711Y1583089D01*
X2620021Y1584547D01*
X2620796Y1585589D01*
X2621881Y1586214D01*
X2622966D01*
X2624051Y1585797D01*
X2624981Y1584756D01*
G01X2631491Y1573714D02*
Y1586214D01*
G01X2638001D02*
Y1573714D01*
G01Y1579964D02*
X2631491D01*
G01X2650246Y1573714D02*
X2644046D01*
Y1586214D01*
X2650246D01*
G01X2647766Y1580172D02*
X2644046D01*
G01X2656136Y1573714D02*
Y1586214D01*
X2659236D01*
X2660476Y1585589D01*
X2661406Y1584756D01*
X2662181Y1583506D01*
X2662801Y1582047D01*
X2662956Y1579964D01*
X2662801Y1577881D01*
X2662181Y1576422D01*
X2661406Y1575172D01*
X2660476Y1574339D01*
X2659236Y1573714D01*
X2656136D01*
G01X2671946Y1573297D02*
X2671636Y1573506D01*
Y1573922D01*
X2671946Y1574131D01*
X2672256Y1573922D01*
Y1573506D01*
X2671946Y1573297D01*
G01X2358381Y1629914D02*
Y1642414D01*
X2365511Y1629914D01*
Y1642414D01*
G01X2374346Y1629914D02*
X2373106Y1630122D01*
X2372021Y1630955D01*
X2371091Y1632206D01*
X2370471Y1633664D01*
X2370161Y1635331D01*
Y1636997D01*
X2370471Y1638664D01*
X2371091Y1640122D01*
X2372021Y1641372D01*
X2373106Y1642206D01*
X2374346Y1642414D01*
X2375586Y1642206D01*
X2376671Y1641372D01*
X2377601Y1640122D01*
X2378221Y1638664D01*
X2378531Y1636997D01*
Y1635331D01*
X2378221Y1633664D01*
X2377601Y1632206D01*
X2376671Y1630955D01*
X2375586Y1630122D01*
X2374346Y1629914D01*
G01X2386746Y1642414D02*
Y1629914D01*
G01X2383181Y1642414D02*
X2390311D01*
G01X2402246Y1629914D02*
X2396046D01*
Y1642414D01*
X2402246D01*
G01X2399766Y1636372D02*
X2396046D01*
G01X2408291Y1631580D02*
X2409531Y1630539D01*
X2410926Y1629914D01*
X2412166D01*
X2413406Y1630539D01*
X2414336Y1631580D01*
X2414801Y1633039D01*
X2414491Y1634497D01*
X2413716Y1635747D01*
X2412321Y1636581D01*
X2410461Y1636997D01*
X2409376Y1637831D01*
X2408911Y1639289D01*
X2409221Y1640747D01*
X2409996Y1641789D01*
X2411081Y1642414D01*
X2412166D01*
X2413251Y1641997D01*
X2414181Y1640956D01*
G01X2423946Y1629497D02*
X2423636Y1629706D01*
Y1630122D01*
X2423946Y1630331D01*
X2424256Y1630122D01*
Y1629706D01*
X2423946Y1629497D01*
G01Y1635122D02*
X2423636Y1635331D01*
Y1635747D01*
X2423946Y1635956D01*
X2424256Y1635747D01*
Y1635331D01*
X2423946Y1635122D01*
G01X2357296Y1658014D02*
Y1767314D01*
X2840896D01*
Y1658014D01*
X2357296D01*
G01X2368301Y1695464D02*
Y1707964D01*
X2374191D01*
G01X2372021Y1701922D02*
X2368301D01*
G01X2381786Y1707964D02*
X2385506D01*
G01X2383646D02*
Y1695464D01*
G01X2381786D02*
X2385506D01*
G01X2396976Y1701714D02*
X2400076D01*
Y1697964D01*
X2399146Y1696714D01*
X2398061Y1695881D01*
X2396511Y1695464D01*
X2394961Y1695881D01*
X2393876Y1696714D01*
X2392946Y1697964D01*
X2392326Y1699422D01*
X2392016Y1701089D01*
Y1702547D01*
X2392326Y1703797D01*
X2392946Y1705256D01*
X2393876Y1706506D01*
X2394806Y1707339D01*
X2396046Y1707964D01*
X2397131D01*
X2398371Y1707547D01*
X2399301Y1706714D01*
G01X2405036Y1707964D02*
Y1699006D01*
X2405656Y1697130D01*
X2406896Y1695881D01*
X2408446Y1695464D01*
X2409996Y1695881D01*
X2411236Y1697130D01*
X2411856Y1699006D01*
Y1707964D01*
G01X2417746Y1695464D02*
Y1707964D01*
X2421621D01*
X2422861Y1707339D01*
X2423636Y1706506D01*
X2423946Y1704839D01*
X2423636Y1703172D01*
X2422706Y1702131D01*
X2421621Y1701506D01*
X2417746D01*
G01X2421621D02*
X2423946Y1695464D01*
G01X2436346D02*
X2430146D01*
Y1707964D01*
X2436346D01*
G01X2433866Y1701922D02*
X2430146D01*
G01X2357296Y1686114D02*
X2840896D01*
G01X2357296Y1742314D02*
X2840896D01*
G01X2357296Y1714214D02*
X2840896D01*
G01X2447196D02*
Y1658014D01*
G01X2463936Y1755231D02*
X2464556Y1755856D01*
X2465021Y1756897D01*
X2465331Y1758356D01*
X2465021Y1759606D01*
X2464401Y1760439D01*
X2463316Y1761064D01*
X2459131D01*
Y1748564D01*
X2464246D01*
X2465331Y1749397D01*
X2465951Y1750647D01*
X2466261Y1752106D01*
X2465951Y1753564D01*
X2465021Y1754814D01*
X2463936Y1755231D01*
X2459131D01*
G01X2471221Y1748564D02*
X2475096Y1761064D01*
X2478971Y1748564D01*
G01X2477576Y1752939D02*
X2472616D01*
G01X2490906Y1760022D02*
X2489976Y1760647D01*
X2488891Y1761064D01*
X2487651D01*
X2486256Y1760439D01*
X2485171Y1759397D01*
X2484396Y1758147D01*
X2483776Y1756064D01*
X2483621Y1754189D01*
X2483931Y1752314D01*
X2484396Y1751064D01*
X2485326Y1749814D01*
X2486411Y1748981D01*
X2487496Y1748564D01*
X2488581D01*
X2489666Y1748981D01*
X2490596Y1749605D01*
X2491371Y1750439D01*
G01X2496486Y1748564D02*
Y1761064D01*
G01X2502376D02*
X2496486Y1753355D01*
G01X2503306Y1748564D02*
X2499121Y1756897D01*
G01X2508886Y1748564D02*
Y1761064D01*
X2511986D01*
X2513226Y1760439D01*
X2514156Y1759606D01*
X2514931Y1758356D01*
X2515551Y1756897D01*
X2515706Y1754814D01*
X2515551Y1752731D01*
X2514931Y1751272D01*
X2514156Y1750022D01*
X2513226Y1749189D01*
X2511986Y1748564D01*
X2508886D01*
G01X2521596D02*
Y1761064D01*
X2525471D01*
X2526711Y1760439D01*
X2527486Y1759606D01*
X2527796Y1757939D01*
X2527486Y1756272D01*
X2526556Y1755231D01*
X2525471Y1754606D01*
X2521596D01*
G01X2525471D02*
X2527796Y1748564D01*
G01X2535236Y1761064D02*
X2538956D01*
G01X2537096D02*
Y1748564D01*
G01X2535236D02*
X2538956D01*
G01X2546396Y1761064D02*
Y1748564D01*
X2552596D01*
G01X2558796Y1761064D02*
Y1748564D01*
X2564996D01*
G01X2574296Y1748147D02*
X2573986Y1748356D01*
Y1748772D01*
X2574296Y1748981D01*
X2574606Y1748772D01*
Y1748356D01*
X2574296Y1748147D01*
G01Y1753772D02*
X2573986Y1753981D01*
Y1754397D01*
X2574296Y1754606D01*
X2574606Y1754397D01*
Y1753981D01*
X2574296Y1753772D01*
G01X2599096Y1761064D02*
Y1748564D01*
G01X2595531Y1761064D02*
X2602661D01*
G01X2611496Y1748564D02*
X2610256Y1748772D01*
X2609171Y1749605D01*
X2608241Y1750856D01*
X2607621Y1752314D01*
X2607311Y1753981D01*
Y1755647D01*
X2607621Y1757314D01*
X2608241Y1758772D01*
X2609171Y1760022D01*
X2610256Y1760856D01*
X2611496Y1761064D01*
X2612736Y1760856D01*
X2613821Y1760022D01*
X2614751Y1758772D01*
X2615371Y1757314D01*
X2615681Y1755647D01*
Y1753981D01*
X2615371Y1752314D01*
X2614751Y1750856D01*
X2613821Y1749605D01*
X2612736Y1748772D01*
X2611496Y1748564D01*
G01X2620796D02*
Y1761064D01*
X2624516D01*
X2625756Y1760439D01*
X2626686Y1758981D01*
X2626996Y1757314D01*
X2626686Y1755647D01*
X2625911Y1754397D01*
X2624516Y1753772D01*
X2620796D01*
G01X2648696Y1761064D02*
Y1748564D01*
G01X2646526Y1756897D02*
X2650866D01*
G01X2661096Y1748564D02*
X2660166Y1748772D01*
X2659236Y1749605D01*
X2658616Y1751064D01*
X2658306Y1752731D01*
X2658616Y1754397D01*
X2659236Y1755856D01*
X2660166Y1756689D01*
X2661096Y1756897D01*
X2662026Y1756689D01*
X2662956Y1755856D01*
X2663576Y1754397D01*
X2663731Y1752731D01*
X2663576Y1751064D01*
X2662956Y1749605D01*
X2662026Y1748772D01*
X2661096Y1748564D01*
G01X2682796Y1761064D02*
Y1748564D01*
X2688996D01*
G01X2695351Y1753772D02*
X2696436Y1755231D01*
X2697366Y1756064D01*
X2698606Y1756481D01*
X2699691Y1756064D01*
X2700466Y1755231D01*
X2701086Y1753981D01*
X2701241Y1752522D01*
X2701086Y1751272D01*
X2700466Y1750022D01*
X2699536Y1748981D01*
X2698451Y1748564D01*
X2697211Y1748981D01*
X2696126Y1750230D01*
X2695506Y1752106D01*
X2695351Y1754189D01*
X2695661Y1756897D01*
X2696126Y1758356D01*
X2696901Y1759814D01*
X2697986Y1760856D01*
X2699071Y1761064D01*
X2700156Y1760647D01*
X2700931Y1759606D01*
G01X2706821Y1761064D02*
X2710696Y1748564D01*
X2714571Y1761064D01*
G01X2726506Y1760022D02*
X2725576Y1760647D01*
X2724491Y1761064D01*
X2723251D01*
X2721856Y1760439D01*
X2720771Y1759397D01*
X2719996Y1758147D01*
X2719376Y1756064D01*
X2719221Y1754189D01*
X2719531Y1752314D01*
X2719996Y1751064D01*
X2720926Y1749814D01*
X2722011Y1748981D01*
X2723096Y1748564D01*
X2724181D01*
X2725266Y1748981D01*
X2726196Y1749605D01*
X2726971Y1750439D01*
G01X2738906Y1760022D02*
X2737976Y1760647D01*
X2736891Y1761064D01*
X2735651D01*
X2734256Y1760439D01*
X2733171Y1759397D01*
X2732396Y1758147D01*
X2731776Y1756064D01*
X2731621Y1754189D01*
X2731931Y1752314D01*
X2732396Y1751064D01*
X2733326Y1749814D01*
X2734411Y1748981D01*
X2735496Y1748564D01*
X2736581D01*
X2737666Y1748981D01*
X2738596Y1749605D01*
X2739371Y1750439D01*
G01X2471221Y1723564D02*
X2475096Y1736064D01*
X2478971Y1723564D01*
G01X2477576Y1727939D02*
X2472616D01*
G01X2484396Y1736064D02*
Y1723564D01*
X2490596D01*
G01X2496796Y1736064D02*
Y1723564D01*
X2502996D01*
G01X2521286Y1736064D02*
Y1727106D01*
X2521906Y1725230D01*
X2523146Y1723981D01*
X2524696Y1723564D01*
X2526246Y1723981D01*
X2527486Y1725230D01*
X2528106Y1727106D01*
Y1736064D01*
G01X2533531Y1723564D02*
Y1736064D01*
X2540661Y1723564D01*
Y1736064D01*
G01X2547636D02*
X2551356D01*
G01X2549496D02*
Y1723564D01*
G01X2547636D02*
X2551356D01*
G01X2561896Y1736064D02*
Y1723564D01*
G01X2558331Y1736064D02*
X2565461D01*
G01X2571041Y1725230D02*
X2572281Y1724189D01*
X2573676Y1723564D01*
X2574916D01*
X2576156Y1724189D01*
X2577086Y1725230D01*
X2577551Y1726689D01*
X2577241Y1728147D01*
X2576466Y1729397D01*
X2575071Y1730231D01*
X2573211Y1730647D01*
X2572126Y1731481D01*
X2571661Y1732939D01*
X2571971Y1734397D01*
X2572746Y1735439D01*
X2573831Y1736064D01*
X2574916D01*
X2576001Y1735647D01*
X2576931Y1734606D01*
G01X2595221Y1723564D02*
X2599096Y1736064D01*
X2602971Y1723564D01*
G01X2601576Y1727939D02*
X2596616D01*
G01X2608396Y1723564D02*
Y1736064D01*
X2612271D01*
X2613511Y1735439D01*
X2614286Y1734606D01*
X2614596Y1732939D01*
X2614286Y1731272D01*
X2613356Y1730231D01*
X2612271Y1729606D01*
X2608396D01*
G01X2612271D02*
X2614596Y1723564D01*
G01X2626996D02*
X2620796D01*
Y1736064D01*
X2626996D01*
G01X2624516Y1730022D02*
X2620796D01*
G01X2646836Y1736064D02*
X2650556D01*
G01X2648696D02*
Y1723564D01*
G01X2646836D02*
X2650556D01*
G01X2657531D02*
Y1736064D01*
X2664661Y1723564D01*
Y1736064D01*
G01X2681866Y1723564D02*
Y1736064D01*
X2685896Y1725647D01*
X2689926Y1736064D01*
Y1723564D01*
G01X2696436Y1736064D02*
X2700156D01*
G01X2698296D02*
Y1723564D01*
G01X2696436D02*
X2700156D01*
G01X2707596Y1736064D02*
Y1723564D01*
X2713796D01*
G01X2719841Y1725230D02*
X2721081Y1724189D01*
X2722476Y1723564D01*
X2723716D01*
X2724956Y1724189D01*
X2725886Y1725230D01*
X2726351Y1726689D01*
X2726041Y1728147D01*
X2725266Y1729397D01*
X2723871Y1730231D01*
X2722011Y1730647D01*
X2720926Y1731481D01*
X2720461Y1732939D01*
X2720771Y1734397D01*
X2721546Y1735439D01*
X2722631Y1736064D01*
X2723716D01*
X2724801Y1735647D01*
X2725731Y1734606D01*
G01X2516946Y1665814D02*
Y1678314D01*
X2515086Y1675814D01*
G01Y1665814D02*
X2518806D01*
G01X2531206D02*
Y1678314D01*
X2525471Y1669356D01*
X2533221D01*
G01X2541746Y1665397D02*
X2541436Y1665606D01*
Y1666022D01*
X2541746Y1666231D01*
X2542056Y1666022D01*
Y1665606D01*
X2541746Y1665397D01*
G01X2554146Y1665814D02*
Y1678314D01*
X2552286Y1675814D01*
G01Y1665814D02*
X2556006D01*
G01X2566236D02*
X2566546Y1668522D01*
X2567011Y1670814D01*
X2567631Y1672897D01*
X2568406Y1675189D01*
X2569646Y1678314D01*
X2563446D01*
G01X2519891Y1697130D02*
X2521131Y1696089D01*
X2522526Y1695464D01*
X2523766D01*
X2525006Y1696089D01*
X2525936Y1697130D01*
X2526401Y1698589D01*
X2526091Y1700047D01*
X2525316Y1701297D01*
X2523921Y1702131D01*
X2522061Y1702547D01*
X2520976Y1703381D01*
X2520511Y1704839D01*
X2520821Y1706297D01*
X2521596Y1707339D01*
X2522681Y1707964D01*
X2523766D01*
X2524851Y1707547D01*
X2525781Y1706506D01*
G01X2533686Y1707964D02*
X2537406D01*
G01X2535546D02*
Y1695464D01*
G01X2533686D02*
X2537406D01*
G01X2545001Y1707964D02*
X2550891D01*
X2545001Y1695464D01*
X2550891D01*
G01X2563446D02*
X2557246D01*
Y1707964D01*
X2563446D01*
G01X2560966Y1701922D02*
X2557246D01*
G01X2665746Y1665814D02*
Y1678314D01*
X2669466D01*
X2670706Y1677689D01*
X2671636Y1676231D01*
X2671946Y1674564D01*
X2671636Y1672897D01*
X2670861Y1671647D01*
X2669466Y1671022D01*
X2665746D01*
G01X2678146Y1678314D02*
Y1665814D01*
X2684346D01*
G01X2689771D02*
X2693646Y1678314D01*
X2697521Y1665814D01*
G01X2696126Y1670189D02*
X2691166D01*
G01X2706046Y1678314D02*
Y1665814D01*
G01X2702481Y1678314D02*
X2709611D01*
G01X2721546Y1665814D02*
X2715346D01*
Y1678314D01*
X2721546D01*
G01X2719066Y1672272D02*
X2715346D01*
G01X2727436Y1665814D02*
Y1678314D01*
X2730536D01*
X2731776Y1677689D01*
X2732706Y1676856D01*
X2733481Y1675606D01*
X2734101Y1674147D01*
X2734256Y1672064D01*
X2734101Y1669981D01*
X2733481Y1668522D01*
X2732706Y1667272D01*
X2731776Y1666439D01*
X2730536Y1665814D01*
X2727436D01*
G01X2636296Y1714214D02*
Y1658014D01*
G01X2665746Y1695464D02*
Y1707964D01*
X2669466D01*
X2670706Y1707339D01*
X2671636Y1705881D01*
X2671946Y1704214D01*
X2671636Y1702547D01*
X2670861Y1701297D01*
X2669466Y1700672D01*
X2665746D01*
G01X2678146Y1707964D02*
Y1695464D01*
X2684346D01*
G01X2689771D02*
X2693646Y1707964D01*
X2697521Y1695464D01*
G01X2696126Y1699839D02*
X2691166D01*
G01X2706046Y1707964D02*
Y1695464D01*
G01X2702481Y1707964D02*
X2709611D01*
G01X2721546Y1695464D02*
X2715346D01*
Y1707964D01*
X2721546D01*
G01X2719066Y1701922D02*
X2715346D01*
G01X2727436Y1695464D02*
Y1707964D01*
X2730536D01*
X2731776Y1707339D01*
X2732706Y1706506D01*
X2733481Y1705256D01*
X2734101Y1703797D01*
X2734256Y1701714D01*
X2734101Y1699631D01*
X2733481Y1698172D01*
X2732706Y1696922D01*
X2731776Y1696089D01*
X2730536Y1695464D01*
X2727436D01*
G01X2763396Y1714214D02*
Y1658014D01*
G01X2789746Y1665814D02*
Y1678314D01*
X2787886Y1675814D01*
G01Y1665814D02*
X2791606D01*
G01X2799201Y1676231D02*
X2800131Y1677480D01*
X2801216Y1678106D01*
X2802456Y1678314D01*
X2804006Y1677897D01*
X2805091Y1676856D01*
X2805401Y1675606D01*
X2805246Y1674355D01*
X2804626Y1673314D01*
X2801526Y1671231D01*
X2800131Y1669772D01*
X2799201Y1667689D01*
X2798891Y1665814D01*
X2805401D01*
G01X2814546D02*
X2815631Y1666022D01*
X2816871Y1666647D01*
X2817646Y1667689D01*
X2817956Y1669147D01*
X2817646Y1670605D01*
X2816716Y1671856D01*
X2815321Y1672481D01*
X2813771D01*
X2812841Y1672897D01*
X2812066Y1673939D01*
X2811756Y1675397D01*
X2812221Y1676856D01*
X2813306Y1677897D01*
X2814546Y1678314D01*
X2815786Y1677897D01*
X2816871Y1676856D01*
X2817336Y1675397D01*
X2817026Y1673939D01*
X2816251Y1672897D01*
X2815321Y1672481D01*
X2813771D01*
X2812376Y1671856D01*
X2811446Y1670605D01*
X2811136Y1669147D01*
X2811446Y1667689D01*
X2812221Y1666647D01*
X2813461Y1666022D01*
X2814546Y1665814D01*
G01X2789746Y1695464D02*
X2788506Y1695672D01*
X2787421Y1696505D01*
X2786491Y1697756D01*
X2785871Y1699214D01*
X2785561Y1700881D01*
Y1702547D01*
X2785871Y1704214D01*
X2786491Y1705672D01*
X2787421Y1706922D01*
X2788506Y1707756D01*
X2789746Y1707964D01*
X2790986Y1707756D01*
X2792071Y1706922D01*
X2793001Y1705672D01*
X2793621Y1704214D01*
X2793931Y1702547D01*
Y1700881D01*
X2793621Y1699214D01*
X2793001Y1697756D01*
X2792071Y1696505D01*
X2790986Y1695672D01*
X2789746Y1695464D01*
G01X2790986Y1698797D02*
X2792846Y1695464D01*
G01X2802146Y1707964D02*
Y1695464D01*
G01X2798581Y1707964D02*
X2805711D01*
G01X2814546Y1695464D02*
Y1701089D01*
X2811446Y1707964D01*
G01X2817646D02*
X2814546Y1701089D01*
G01X0Y-137756D02*
G03X15000Y-152756I15000J0D01*
G01X0Y-137756D02*
G03X15000Y-152756I15000J0D01*
G01X0Y-11811D02*
Y-137756D01*
G01Y-11811D02*
Y-137756D01*
G01X854331Y-152756D02*
X15000D01*
G01X854331D02*
X15000D01*
G01X23622Y-7874D02*
G03Y0I0J3937D01*
G01Y-7874D02*
G03Y0I0J3937D01*
G01X0Y3937D02*
G03X3937Y0I3937J0D01*
G01Y-7874D02*
X23622D01*
G01X0Y3937D02*
G03X3937Y0I3937J0D01*
G01Y-7874D02*
X23622D01*
G01X3937D02*
G03X0Y-11811I0J-3937D01*
G01X3937Y-7874D02*
G03X0Y-11811I0J-3937D01*
G01X3937Y0D02*
X397638D01*
G01X3937D02*
X397638D01*
G01X0Y1370866D02*
Y3937D01*
G01Y1370866D02*
Y3937D01*
G01X3937Y1374803D02*
G03X0Y1370866I0J-3937D01*
G01X3937Y1374803D02*
G03X0Y1370866I0J-3937D01*
G01X23622Y1374803D02*
G03Y1382677I0J3937D01*
G01Y1374803D02*
G03Y1382677I0J3937D01*
G01X3937D02*
X23622D01*
G01X0Y1386614D02*
G03X3937Y1382677I3937J0D01*
G01D02*
X23622D01*
G01X0Y1386614D02*
G03X3937Y1382677I3937J0D01*
G01Y1374803D02*
X746850D01*
G01D02*
X3937D01*
G01X0Y1386614D02*
Y1643268D01*
G01Y1386614D02*
Y1643268D01*
G01X15000Y1658268D02*
G03X0Y1643268I0J-15000D01*
G01X15000Y1658268D02*
G03X0Y1643268I0J-15000D01*
G01X775591Y1658268D02*
X15000D01*
G01X775591D02*
X15000D01*
G01X54331Y-7874D02*
X323228D01*
G01X54331D02*
X323228D01*
G01X54331Y0D02*
G03Y-7874I0J-3937D01*
G01Y0D02*
G03Y-7874I0J-3937D01*
G01Y1382677D02*
G03Y1374803I0J-3937D01*
G01Y1382677D02*
G03Y1374803I0J-3937D01*
G01Y1382677D02*
X353740D01*
G01X54331D02*
X353740D01*
G01X114295Y378885D02*
G03X148106I16905J-13531D01*
G01X114295D02*
G03X148106I16905J-13531D01*
G01X114295D02*
G03X121220Y392016I-30737J24602D01*
G01X114295Y378885D02*
G03X121220Y392016I-30737J24602D01*
G01X114295Y831641D02*
G03X121220Y844772I-30737J24601D01*
G01X114295Y831641D02*
G03X121220Y844772I-30737J24602D01*
G01X114295Y831641D02*
G03X148106I16905J-13531D01*
G01X114295D02*
G03X148106I16905J-13531D01*
G01X114295Y1284397D02*
G03X148106I16905J-13531D01*
G01X114295D02*
G03X148106I16905J-13531D01*
G01X114295D02*
G03X121220Y1297528I-30737J24601D01*
G01X114295Y1284397D02*
G03X121220Y1297528I-30737J24602D01*
G01X141181Y392016D02*
G03X121220I-9980J-3039D01*
G01X141181D02*
G03X148106Y378885I37662J11471D01*
G01X141181Y392016D02*
G03X121220I-9980J-3039D01*
G01X141181D02*
G03X148106Y378885I37662J11471D01*
G01X141181Y844772D02*
G03X148106Y831641I37662J11471D01*
G01X141181Y844772D02*
G03X148106Y831641I37662J11471D01*
G01X141181Y844772D02*
G03X121220I-9980J-3040D01*
G01X141181D02*
G03X121220I-9980J-3039D01*
G01X141181Y1297528D02*
G03X121220I-9980J-3040D01*
G01X141181D02*
G03X148106Y1284397I37662J11471D01*
G01X141181Y1297528D02*
G03X121220I-9980J-3040D01*
G01X141181D02*
G03X148106Y1284397I37662J11471D01*
G01X323228Y-7874D02*
G03Y0I0J3937D01*
G01Y-7874D02*
G03Y0I0J3937D01*
G01X362598D02*
G03Y-7874I0J-3937D01*
G01Y0D02*
G03Y-7874I0J-3937D01*
G01X362327Y378885D02*
G03X396138I16905J-13531D01*
G01X362327D02*
G03X396138I16905J-13531D01*
G01X362327D02*
G03X369252Y392016I-30737J24602D01*
G01X362327Y378885D02*
G03X369252Y392016I-30737J24602D01*
G01X362327Y831641D02*
G03X369252Y844772I-30737J24602D01*
G01X362327Y831641D02*
G03X369252Y844772I-30737J24602D01*
G01X362327Y831641D02*
G03X396138I16905J-13531D01*
G01X362327D02*
G03X396138I16905J-13531D01*
G01X362327Y1284397D02*
G03X396138I16905J-13531D01*
G01X362327D02*
G03X396138I16905J-13531D01*
G01X362327D02*
G03X369252Y1297528I-30737J24602D01*
G01X362327Y1284397D02*
G03X369252Y1297528I-30737J24602D01*
G01X353740Y1374803D02*
G03Y1382677I0J3937D01*
G01Y1374803D02*
G03Y1382677I0J3937D01*
G01X401575Y3937D02*
Y55118D01*
G01X397638Y0D02*
G03X401575Y3937I0J3937D01*
G01X409449D02*
Y51181D01*
G01X397638Y-7874D02*
G03X409449Y3937I0J11811D01*
G01X397638Y0D02*
G03X401575Y3937I0J3937D01*
G01D02*
Y55118D01*
G01X409449Y3937D02*
Y51181D01*
G01X397638Y-7874D02*
G03X409449Y3937I0J11811D01*
G01X362598Y-7874D02*
X397638D01*
G01X362598D02*
X397638D01*
G01X405512Y59055D02*
G03X401575Y55118I0J-3937D01*
G01X405512Y59055D02*
G03X401575Y55118I0J-3937D01*
G01X405512Y59055D02*
X586614D01*
G01X409449Y51181D02*
X582677D01*
G01X405512Y59055D02*
X586614D01*
G01X409449Y51181D02*
X582677D01*
G01X389213Y392016D02*
G03X396138Y378885I37662J11471D01*
G01X389213Y392016D02*
G03X396138Y378885I37662J11471D01*
G01X389213Y392016D02*
G03X369252I-9981J-3039D01*
G01X389213D02*
G03X369252I-9981J-3039D01*
G01X389213Y844772D02*
G03X396138Y831641I37662J11471D01*
G01X389213Y844772D02*
G03X396138Y831641I37662J11471D01*
G01X389213Y844772D02*
G03X369252I-9981J-3040D01*
G01X389213D02*
G03X369252I-9981J-3039D01*
G01X389213Y1297528D02*
G03X396138Y1284397I37662J11471D01*
G01X389213Y1297528D02*
G03X396138Y1284397I37662J11471D01*
G01X389213Y1297528D02*
G03X369252I-9981J-3040D01*
G01X389213D02*
G03X369252I-9981J-3040D01*
G01X393110Y1382677D02*
G03Y1374803I0J-3937D01*
G01Y1382677D02*
X692520D01*
G01X393110D02*
X692520D01*
G01X393110D02*
G03Y1374803I0J-3937D01*
G01X523327Y829921D02*
G03X483169I-20079J0D01*
G01X523327D02*
G03I-20079J0D01*
G01X483169D02*
G03X523327I20079J0D01*
G01X594488Y-7874D02*
X628765D01*
G01X594488D02*
X628765D01*
G01X590551Y55118D02*
Y3937D01*
G01D02*
G03X594488Y0I3937J0D01*
G01X582677Y51181D02*
Y3937D01*
G01D02*
G03X594488Y-7874I11811J0D01*
G01X590551Y55118D02*
Y3937D01*
G01D02*
G03X594488Y0I3937J0D01*
G01X582677Y51181D02*
Y3937D01*
G01D02*
G03X594488Y-7874I11811J0D01*
G01Y0D02*
X783465D01*
G01X594488D02*
X783465D01*
G01X590551Y55118D02*
G03X586614Y59055I-3937J0D01*
G01X590551Y55118D02*
G03X586614Y59055I-3937J0D01*
G01X628765Y-7874D02*
G03Y0I0J3937D01*
G01Y-7874D02*
G03Y0I0J3937D01*
G01X610358Y378885D02*
G03X644169I16906J-13531D01*
G01X610358D02*
G03X644169I16906J-13531D01*
G01X637244Y392016D02*
G03X644169Y378885I37662J11471D01*
G01X637244Y392016D02*
G03X644169Y378885I37662J11471D01*
G01X637244Y392016D02*
G03X617283I-9980J-3039D01*
G01X637244D02*
G03X617283I-9980J-3039D01*
G01X610358Y378885D02*
G03X617283Y392016I-30737J24602D01*
G01X610358Y378885D02*
G03X617283Y392016I-30737J24602D01*
G01X637244Y844772D02*
G03X644169Y831641I37662J11471D01*
G01X637244Y844772D02*
G03X644169Y831641I37662J11471D01*
G01X610358D02*
G03X617283Y844772I-30737J24601D01*
G01X610358Y831641D02*
G03X617283Y844772I-30737J24602D01*
G01X610358Y831641D02*
G03X644169I16906J-13531D01*
G01X610358D02*
G03X644169I16906J-13531D01*
G01X637244Y844772D02*
G03X617283I-9980J-3040D01*
G01X637244D02*
G03X617283I-9980J-3039D01*
G01X610358Y1284397D02*
G03X644169I16906J-13531D01*
G01X610358D02*
G03X644169I16906J-13531D01*
G01X637244Y1297528D02*
G03X644169Y1284397I37662J11471D01*
G01X637244Y1297528D02*
G03X644169Y1284397I37662J11471D01*
G01X610358D02*
G03X617283Y1297528I-30737J24601D01*
G01X637244D02*
G03X617283I-9980J-3040D01*
G01X610358Y1284397D02*
G03X617283Y1297528I-30737J24602D01*
G01X637244D02*
G03X617283I-9980J-3040D01*
G01X659474Y0D02*
G03Y-7874I0J-3937D01*
G01Y0D02*
G03Y-7874I0J-3937D01*
G01D02*
X780203D01*
G01X659474D02*
X780203D01*
G01X692520Y1374803D02*
G03Y1382677I0J3937D01*
G01Y1374803D02*
G03Y1382677I0J3937D01*
G01X746850Y1374803D02*
G03X750787Y1378740I0J3937D01*
G01X746850Y1374803D02*
G03X750787Y1378740I0J3937D01*
G01X723228Y1382677D02*
G03Y1374803I0J-3937D01*
G01Y1382677D02*
X742913D01*
G01X723228D02*
X742913D01*
G01X723228D02*
G03Y1374803I0J-3937D01*
G01X742913Y1464567D02*
Y1382677D01*
G01Y1464567D02*
Y1382677D01*
G01X754724Y1476378D02*
G03X742913Y1464567I0J-11811D01*
G01X754724Y1476378D02*
G03X742913Y1464567I0J-11811D01*
G01X862205Y-7874D02*
X791339D01*
G01X787402Y-3937D02*
G03X791339Y-7874I3937J0D01*
G01X787402Y-3937D02*
G03X791339Y-7874I3937J0D01*
G01D02*
X862205D01*
G01X858268Y-15748D02*
X791339D01*
G01X858268D02*
X791339D01*
G01X787402Y-3937D02*
G03X783465Y0I-3937J0D01*
G01X787402Y-3937D02*
G03X783465Y0I-3937J0D01*
G01X780203Y-7874D02*
G03X791339Y-15748I11136J3937D01*
G01X780203Y-7874D02*
G03X791339Y-15748I11136J3937D01*
G01X779551Y264712D02*
G03X813362I16905J-13531D01*
G01X779551D02*
G03X813362I16905J-13531D01*
G01X779551D02*
G03X786476Y277843I-30737J24601D01*
G01X806437D02*
G03X786476I-9981J-3040D01*
G01X779551Y264712D02*
G03X786476Y277843I-30737J24602D01*
G01X806437D02*
G03X786476I-9981J-3040D01*
G01X779551Y737153D02*
G03X786476Y750284I-30737J24601D01*
G01X779551Y737154D02*
G03X786476Y750284I-30736J24602D01*
G01X779551Y737153D02*
G03X813362I16905J-13531D01*
G01X779551D02*
G03X813362I16905J-13531D01*
G01X806437Y750284D02*
G03X786476I-9981J-3040D01*
G01X806437D02*
G03X786476I-9981J-3040D01*
G01X750787Y1464567D02*
Y1378740D01*
G01Y1464567D02*
Y1378740D01*
G01X783465Y1468504D02*
G03X787402Y1472441I0J3937D01*
G01X783465Y1468504D02*
G03X787402Y1472441I0J3937D01*
G01X783465Y1468504D02*
X754724D01*
G01D02*
G03X750787Y1464567I0J-3937D01*
G01X783465Y1468504D02*
X754724D01*
G01D02*
G03X750787Y1464567I0J-3937D01*
G01X779528Y1476378D02*
X754724D01*
G01X779528D02*
X754724D01*
G01X787402Y1654331D02*
Y1472441D01*
G01X779528Y1596063D02*
Y1476378D01*
G01X787402Y1654331D02*
Y1472441D01*
G01X779528Y1596063D02*
Y1476378D01*
G01X787402Y1596063D02*
G03X779528I-3937J0D01*
G01X787402D02*
G03X779528I-3937J0D01*
G01X1216535Y1658268D02*
X791339D01*
G01D02*
G03X787402Y1654331I0J-3937D01*
G01X779528D02*
G03X775591Y1658268I-3937J0D01*
G01X1216535D02*
X791339D01*
G01D02*
G03X787402Y1654331I0J-3937D01*
G01X779528D02*
G03X775591Y1658268I-3937J0D01*
G01X779528Y1654331D02*
Y1626772D01*
G01D02*
G03X787402I3937J0D01*
G01X779528Y1654331D02*
Y1626772D01*
G01D02*
G03X787402I3937J0D01*
G01X806437Y277843D02*
G03X813362Y264712I37662J11471D01*
G01X806437Y277843D02*
G03X813362Y264712I37662J11471D01*
G01X806437Y750284D02*
G03X813362Y737153I37662J11471D01*
G01X806437Y750284D02*
G03X813362Y737154I37661J11472D01*
G01X866142Y-148819D02*
Y-11811D01*
G01Y-148819D02*
G03X870079Y-152756I3937J0D01*
G01X866142Y-11811D02*
Y-148819D01*
G01D02*
G03X870079Y-152756I3937J0D01*
G01X866142Y-129134D02*
G03X858268I-3937J0D01*
G01X866142D02*
G03X858268I-3937J0D01*
G01Y-148819D02*
Y-129134D01*
G01X854331Y-152756D02*
G03X858268Y-148819I0J3937D01*
G01D02*
Y-129134D01*
G01X854331Y-152756D02*
G03X858268Y-148819I0J3937D01*
G01X1177165Y-152756D02*
X870079D01*
G01D02*
X1177165D01*
G01X858268Y-98425D02*
Y-15748D01*
G01Y-98425D02*
Y-15748D01*
G01Y-98425D02*
G03X866142I3937J0D01*
G01X858268D02*
G03X866142I3937J0D01*
G01Y-11811D02*
G03X862205Y-7874I-3937J0D01*
G01X866142Y-11811D02*
G03X862205Y-7874I-3937J0D01*
G01X927032Y-57820D02*
G03X962731I17850J-12259D01*
G01X927032Y-57821D02*
G03X962732I17850J-12258D01*
G01X927032Y-57820D02*
G03X935199Y-42571I-64908J44575D01*
G01X954565D02*
G03X935199I-9683J-3885D01*
G01X927032Y-57821D02*
G03X935199Y-42571I-64909J44573D01*
G01X954564D02*
G03X935199I-9682J-3885D01*
G01X944512Y1089122D02*
G03X978323I16905J-13531D01*
G01X944512Y1089121D02*
G03X978323I16905J-13531D01*
G01X944512Y1431641D02*
G03X978323I16905J-13531D01*
G01X944512D02*
G03X978323I16905J-13531D01*
G01X954565Y-42571D02*
G03X962731Y-57820I73077J29322D01*
G01X954564Y-42570D02*
G03X962732Y-57821I73076J29324D01*
G01X971398Y1102252D02*
G03X978323Y1089122I37661J11472D01*
G01X971398Y1102252D02*
G03X978323Y1089121I37662J11471D01*
G01X971398Y1102252D02*
G03X951437I-9980J-3039D01*
G01X971398D02*
G03X951437I-9980J-3039D01*
G01X944512Y1089122D02*
G03X951437Y1102252I-30737J24602D01*
G01X944512Y1089121D02*
G03X951437Y1102252I-30737J24602D01*
G01X971398Y1444772D02*
G03X978323Y1431641I37662J11471D01*
G01X971398Y1444772D02*
G03X978323Y1431641I37662J11471D01*
G01X971398Y1444772D02*
G03X951437I-9980J-3040D01*
G01X944512Y1431641D02*
G03X951437Y1444772I-30737J24602D01*
G01X944512Y1431641D02*
G03X951437Y1444772I-30737J24602D01*
G01X971398D02*
G03X951437I-9980J-3039D01*
G01X1181102Y-148819D02*
Y-3937D01*
G01X1177165Y-152756D02*
G03X1181102Y-148819I0J3937D01*
G01X1177165Y-152756D02*
G03X1181102Y-148819I0J3937D01*
G01D02*
Y-3937D01*
G01Y-94488D02*
G03X1188976I3937J0D01*
G01X1181102D02*
G03X1188976I3937J0D01*
G01Y-125197D02*
G03X1181102I-3937J0D01*
G01X1188976D02*
G03X1181102I-3937J0D01*
G01X1185039Y0D02*
G03X1181102Y-3937I0J-3937D01*
G01X1185039Y0D02*
G03X1181102Y-3937I0J-3937D01*
G01X1164984Y557626D02*
G03X1198795I16906J-13531D01*
G01X1164984Y557625D02*
G03X1198795I16906J-13531D01*
G01X1191870Y570756D02*
G03X1171909I-9980J-3039D01*
G01X1191870D02*
G03X1171909I-9980J-3039D01*
G01X1164984Y557626D02*
G03X1171909Y570756I-30736J24602D01*
G01X1164984Y557625D02*
G03X1171909Y570756I-30737J24602D01*
G01X1164984Y971011D02*
G03X1198795I16906J-13531D01*
G01X1164984D02*
G03X1198795I16906J-13531D01*
G01X1191870Y984142D02*
G03X1171909I-9980J-3040D01*
G01X1191870D02*
G03X1171909I-9980J-3039D01*
G01X1164984Y971011D02*
G03X1171909Y984142I-30737J24602D01*
G01X1164984Y971011D02*
G03X1171909Y984142I-30737J24602D01*
G01X1164173Y1378740D02*
Y1468504D01*
G01X1930906Y1374803D02*
X1168110D01*
G01X1164173Y1378740D02*
G03X1168110Y1374803I3937J0D01*
G01X1172047Y1382677D02*
Y1464567D01*
G01X1195669Y1382677D02*
X1172047D01*
G01X1930906Y1374803D02*
X1168110D01*
G01X1164173Y1378740D02*
G03X1168110Y1374804I3937J1D01*
G01X1164173Y1378740D02*
Y1468504D01*
G01X1172047Y1382677D02*
Y1464567D01*
G01X1195669Y1382677D02*
X1172047D01*
G01X1168110Y1472441D02*
G03X1164173Y1468504I0J-3937D01*
G01X1168110Y1472441D02*
G03X1164173Y1468504I0J-3937D01*
G01X1172047Y1464567D02*
X1216535D01*
G01X1172047D02*
X1216535D01*
G01X1168110Y1472441D02*
X1216535D01*
G01X1168110D02*
X1216535D01*
G01X1164984Y1561563D02*
G03X1171909Y1574693I-30736J24602D01*
G01X1164984Y1561562D02*
G03X1171909Y1574693I-30737J24602D01*
G01X1164984Y1561563D02*
G03X1198795I16906J-13531D01*
G01X1164984Y1561562D02*
G03X1198795I16906J-13531D01*
G01X1191870Y1574693D02*
G03X1171909I-9980J-3039D01*
G01X1191870D02*
G03X1171909I-9980J-3039D01*
G01X1188976Y-148819D02*
Y-125197D01*
G01Y-148819D02*
G03X1192913Y-152756I3937J0D01*
G01X1188976Y-148819D02*
Y-125197D01*
G01Y-148819D02*
G03X1192913Y-152756I3937J0D01*
G01D02*
X1919843D01*
G01X1192913D02*
X1919843D01*
G01X1188976Y-94488D02*
Y-7874D01*
G01Y-94488D02*
Y-7874D01*
G01X1185039Y0D02*
X1366142D01*
G01X1188976Y-7874D02*
X1315748D01*
G01X1185039Y0D02*
X1366142D01*
G01X1188976Y-7874D02*
X1315748D01*
G01X1191870Y570756D02*
G03X1198795Y557626I37662J11472D01*
G01X1191870Y570756D02*
G03X1198795Y557626I37662J11472D01*
G01X1191870Y984142D02*
G03X1198795Y971011I37662J11471D01*
G01X1191870Y984142D02*
G03X1198795Y971011I37662J11471D01*
G01X1524606Y1382677D02*
X1226378D01*
G01X1524606D02*
X1226378D01*
G01X1195669Y1374803D02*
G03Y1382677I0J3937D01*
G01X1226378D02*
G03Y1374803I0J-3937D01*
G01X1195669D02*
G03Y1382677I0J3937D01*
G01X1226378D02*
G03Y1374803I0J-3937D01*
G01X1216535Y1464567D02*
G03X1228346Y1476378I0J11811D01*
G01X1216535Y1464567D02*
G03X1228346Y1476378I0J11811D01*
G01Y1592126D02*
Y1476378D01*
G01Y1592126D02*
Y1476378D01*
G01X1220472Y1654331D02*
Y1476378D01*
G01X1216535Y1472441D02*
G03X1220472Y1476378I0J3937D01*
G01X1216535Y1472441D02*
G03X1220472Y1476378I0J3937D01*
G01D02*
Y1654331D01*
G01X1191870Y1574693D02*
G03X1198795Y1561563I37662J11472D01*
G01X1191870Y1574693D02*
G03X1198795Y1561562I37662J11471D01*
G01X1228346Y1592126D02*
G03X1220472I-3937J0D01*
G01X1228346D02*
G03X1220472I-3937J0D01*
G01X1232283Y1658268D02*
X1442382D01*
G01X1232283D02*
G03X1228346Y1654331I0J-3937D01*
G01X1232283Y1658268D02*
X1442382D01*
G01X1232283D02*
G03X1228346Y1654331I0J-3937D01*
G01D02*
Y1622835D01*
G01Y1654331D02*
Y1622835D01*
G01X1220472Y1654331D02*
G03X1216535Y1658268I-3937J0D01*
G01X1220472Y1654331D02*
G03X1216535Y1658268I-3937J0D01*
G01X1220472Y1622835D02*
G03X1228346I3937J0D01*
G01X1220472D02*
G03X1228346I3937J0D01*
G01X1284965Y378885D02*
G03X1318776I16906J-13531D01*
G01X1284965D02*
G03X1318775I16905J-13531D01*
G01X1284965Y831641D02*
G03X1318776I16906J-13531D01*
G01X1284965D02*
G03X1318775I16905J-13531D01*
G01X1284965Y1284397D02*
G03X1318776I16906J-13531D01*
G01X1284965D02*
G03X1318775I16905J-13531D01*
G01X1315748Y-7874D02*
G03Y0I0J3937D01*
G01Y-7874D02*
G03Y0I0J3937D01*
G01X1311850Y392016D02*
G03X1291890I-9980J-3040D01*
G01X1311850D02*
G03X1318776Y378885I37662J11473D01*
G01X1311851Y392016D02*
G03X1291890I-9980J-3039D01*
G01X1311851D02*
G03X1318775Y378885I37663J11469D01*
G01X1284965D02*
G03X1291890Y392016I-30737J24602D01*
G01X1284965Y378885D02*
G03X1291890Y392016I-30737J24602D01*
G01X1284965Y831641D02*
G03X1291890Y844772I-30737J24602D01*
G01X1311850D02*
G03X1318776Y831641I37662J11473D01*
G01X1284965D02*
G03X1291890Y844772I-30737J24602D01*
G01X1311851D02*
G03X1318775Y831641I37663J11469D01*
G01X1311850Y844772D02*
G03X1291890I-9980J-3040D01*
G01X1311851D02*
G03X1291890I-9980J-3039D01*
G01X1284965Y1284397D02*
G03X1291890Y1297528I-30737J24602D01*
G01X1311850D02*
G03X1291890I-9980J-3040D01*
G01X1311850D02*
G03X1318776Y1284397I37661J11473D01*
G01X1284965D02*
G03X1291890Y1297528I-30737J24602D01*
G01X1311851D02*
G03X1291890I-9980J-3040D01*
G01X1311851D02*
G03X1318775Y1284397I37663J11469D01*
G01X1377953Y3937D02*
Y51181D01*
G01Y3937D02*
Y51181D01*
G01X1370079Y3937D02*
Y55118D01*
G01X1366142Y0D02*
G03X1370079Y3937I0J3937D01*
G01X1366142Y-7874D02*
G03X1377953Y3937I0J11811D01*
G01X1346457Y-7874D02*
X1366142D01*
G01Y0D02*
G03X1370079Y3937I0J3937D01*
G01D02*
Y55118D01*
G01X1346457Y-7874D02*
X1366142D01*
G01D02*
G03X1377953Y3937I0J11811D01*
G01X1346457Y0D02*
G03Y-7874I0J-3937D01*
G01Y0D02*
G03Y-7874I0J-3937D01*
G01X1374016Y59055D02*
G03X1370079Y55118I0J-3937D01*
G01X1374016Y59056D02*
G03X1370079Y55118I0J-3937D01*
G01X1374016Y59055D02*
X1555118D01*
G01X1377953Y51181D02*
X1551181D01*
G01X1374016Y59055D02*
X1555118D01*
G01X1377953Y51181D02*
X1551181D01*
G01X1442382Y1658268D02*
G03X1450256I3937J0D01*
G01X1442382D02*
G03X1450256I3937J0D01*
G01D02*
X1919843D01*
G01X1450256D02*
X1919843D01*
G01X1562992Y0D02*
X1930906D01*
G01X1559055Y55118D02*
Y3937D01*
G01D02*
G03X1562992Y0I3937J0D01*
G01Y-7874D02*
X1593701D01*
G01X1559055Y55118D02*
Y3937D01*
G01D02*
G03X1562992Y0I3937J0D01*
G01D02*
X1930906D01*
G01X1562992Y-7874D02*
X1593701D01*
G01X1551181Y51181D02*
Y3937D01*
G01D02*
G03X1562992Y-7874I11811J0D01*
G01X1551181Y51181D02*
Y3937D01*
G01D02*
G03X1562992Y-7874I11811J0D01*
G01X1559055Y55118D02*
G03X1555118Y59055I-3937J0D01*
G01X1559055Y55118D02*
G03X1555118Y59055I-3937J0D01*
G01X1532996Y378885D02*
G03X1566807I16906J-13531D01*
G01X1532996D02*
G03X1566807I16906J-13531D01*
G01X1559882Y392016D02*
G03X1566807Y378885I37662J11471D01*
G01X1559882Y392016D02*
G03X1566807Y378885I37662J11471D01*
G01X1559882Y392016D02*
G03X1539921I-9980J-3039D01*
G01X1559882D02*
G03X1539921I-9980J-3039D01*
G01X1532996Y378885D02*
G03X1539921Y392016I-30737J24602D01*
G01X1532996Y378885D02*
G03X1539921Y392016I-30737J24602D01*
G01X1559882Y844772D02*
G03X1566807Y831641I37662J11471D01*
G01X1559882Y844772D02*
G03X1566807Y831641I37662J11471D01*
G01X1532996D02*
G03X1539921Y844772I-30737J24602D01*
G01X1532996Y831641D02*
G03X1539921Y844772I-30737J24602D01*
G01X1532996Y831641D02*
G03X1566807I16906J-13531D01*
G01X1532996D02*
G03X1566807I16906J-13531D01*
G01X1559882Y844772D02*
G03X1539921I-9980J-3040D01*
G01X1559882D02*
G03X1539921I-9980J-3039D01*
G01X1532996Y1284397D02*
G03X1566807I16906J-13531D01*
G01X1532996D02*
G03X1566807I16906J-13531D01*
G01X1559882Y1297528D02*
G03X1566807Y1284397I37662J11471D01*
G01X1559882Y1297528D02*
G03X1566807Y1284397I37662J11471D01*
G01X1559882Y1297528D02*
G03X1539921I-9980J-3040D01*
G01X1532996Y1284397D02*
G03X1539921Y1297528I-30737J24602D01*
G01X1532996Y1284397D02*
G03X1539921Y1297528I-30737J24602D01*
G01X1559882D02*
G03X1539921I-9980J-3040D01*
G01X1563976Y1382677D02*
G03Y1374803I0J-3937D01*
G01Y1382677D02*
G03Y1374803I0J-3937D01*
G01X1524606D02*
G03Y1382677I0J3937D01*
G01Y1374803D02*
G03Y1382677I0J3937D01*
G01X1864567D02*
X1563976D01*
G01X1864567D02*
X1563976D01*
G01X1593701Y-7874D02*
G03Y0I0J3937D01*
G01Y-7874D02*
G03Y0I0J3937D01*
G01X1633071D02*
G03Y-7874I0J-3937D01*
G01D02*
X1880512D01*
G01X1633071D02*
X1880512D01*
G01X1633071Y0D02*
G03Y-7874I0J-3937D01*
G01X1693996Y829921D02*
G03X1653839I-20078J0D01*
G01X1693996D02*
G03I-20079J0D01*
G01X1653839D02*
G03X1693996I20078J0D01*
G01X1781028Y378885D02*
G03X1814839I16906J-13531D01*
G01X1781028D02*
G03X1814838I16905J-13531D01*
G01X1807913Y392016D02*
G03X1814839Y378885I37662J11473D01*
G01X1807914Y392016D02*
G03X1814838Y378885I37663J11469D01*
G01X1807913Y392016D02*
G03X1787953I-9980J-3040D01*
G01X1807914D02*
G03X1787953I-9980J-3039D01*
G01X1781028Y378885D02*
G03X1787953Y392016I-30737J24602D01*
G01X1781028Y378885D02*
G03X1787953Y392016I-30737J24602D01*
G01X1807913Y844772D02*
G03X1814839Y831641I37662J11473D01*
G01X1807914Y844772D02*
G03X1814838Y831641I37663J11469D01*
G01X1781028D02*
G03X1787953Y844772I-30737J24602D01*
G01X1781028Y831641D02*
G03X1787953Y844772I-30737J24602D01*
G01X1781028Y831641D02*
G03X1814839I16906J-13531D01*
G01X1781028D02*
G03X1814838I16905J-13531D01*
G01X1807913Y844772D02*
G03X1787953I-9980J-3040D01*
G01X1807914D02*
G03X1787953I-9980J-3039D01*
G01X1781028Y1284397D02*
G03X1814839I16906J-13531D01*
G01X1781028D02*
G03X1814838I16905J-13531D01*
G01X1807913Y1297528D02*
G03X1814839Y1284397I37661J11473D01*
G01X1807914Y1297528D02*
G03X1814838Y1284397I37663J11469D01*
G01X1807913Y1297528D02*
G03X1787953I-9980J-3040D01*
G01X1781028Y1284397D02*
G03X1787953Y1297528I-30737J24602D01*
G01X1781028Y1284397D02*
G03X1787953Y1297528I-30737J24602D01*
G01X1807914D02*
G03X1787953I-9980J-3040D01*
G01X1911220Y0D02*
G03Y-7874I0J-3937D01*
G01Y0D02*
G03Y-7874I0J-3937D01*
G01X1880512D02*
G03Y0I0J3937D01*
G01Y-7874D02*
G03Y0I0J3937D01*
G01X1930906Y1382677D02*
X1895276D01*
G01D02*
G03Y1374803I0J-3937D01*
G01X1930906Y1382677D02*
X1895276D01*
G01D02*
G03Y1374803I0J-3937D01*
G01X1864567D02*
G03Y1382677I0J3937D01*
G01Y1374803D02*
G03Y1382677I0J3937D01*
G01X1919843Y-152756D02*
G03X1934843Y-137756I0J15000D01*
G01X1919843Y-152756D02*
G03X1934843Y-137756I0J15000D01*
G01Y-11811D02*
Y-137756D01*
G01Y-11811D02*
Y-137756D01*
G01X1930906Y0D02*
G03X1934843Y3937I0J3937D01*
G01X1930906Y0D02*
G03X1934843Y3937I0J3937D01*
G01Y-11811D02*
G03X1930906Y-7874I-3937J0D01*
G01X1934843Y-11811D02*
G03X1930906Y-7874I-3937J0D01*
G01X1911220D02*
X1930906D01*
G01X1911220D02*
X1930906D01*
G01X1934843Y1370866D02*
Y3937D01*
G01D02*
Y1370866D01*
G01D02*
G03X1930906Y1374803I-3937J0D01*
G01X1934843Y1370866D02*
G03X1930906Y1374803I-3937J0D01*
G01Y1382677D02*
G03X1934843Y1386614I0J3937D01*
G01X1930906Y1382677D02*
G03X1934843Y1386614I0J3937D01*
G01D02*
Y1643268D01*
G01Y1386614D02*
Y1643268D01*
G01D02*
G03X1919843Y1658268I-15000J0D01*
G01X1934843Y1643268D02*
G03X1919843Y1658268I-15000J0D01*
M02*
